FILE_TYPE = MACRO_DRAWING;
SET COLOR_WIRE YELLOW;
SET COLOR_PROP MONO;
SET COLOR_DOT WHITE;
SET COLOR_ARC YELLOW;
SET COLOR_BODY GREEN;
SET COLOR_NOTE MONO;
SET PROP_DISPLAY VALUE;
SET PAGE_NUMBER P41;
FORCEADD GND..1
(-4475 550);
FORCEPROP 3 LASTPIN (-4475 600) SIG_NAME GND\g
J 0
(-4465 610);
DISPLAY 0.659574 (-4465 610);
PAINT MONO (-4465 610);
DISPLAY INVISIBLE (-4465 610);
FORCEPROP 1 LAST VOLTAGE 0.0V
J 0
(-4520 507);
DISPLAY 0.340426 (-4520 507);
PAINT SKYBLUE (-4520 507);
DISPLAY INVISIBLE (-4520 507);
FORCEPROP 1 LAST SIZE 1B
J 0
(-4400 500);
DISPLAY 1.170213 (-4400 500);
PAINT AQUA (-4400 500);
DISPLAY INVISIBLE (-4400 500);
FORCEPROP 2 LAST CDS_LIB mstr_symbols
J 0
(-4475 550);
PAINT ORANGE (-4475 550);
DISPLAY INVISIBLE (-4475 550);
FORCEPROP 1 LAST PATH I275
J 0
(-4400 550);
DISPLAY 0.872340 (-4400 550);
PAINT AQUA (-4400 550);
DISPLAY INVISIBLE (-4400 550);
FORCEPROP 1 LAST BODY_TYPE PLUMBING
J 0
(-4520 507);
DISPLAY 0.340426 (-4520 507);
PAINT GREEN (-4520 507);
DISPLAY INVISIBLE (-4520 507);
FORCEPROP 1 LAST HDL_POWER GND
J 0
(-4475 700);
DISPLAY 1.170213 (-4475 700);
PAINT GREEN (-4475 700);
DISPLAY INVISIBLE (-4475 700);
FORCEADD GND..1
(-2800 525);
FORCEPROP 3 LASTPIN (-2800 575) SIG_NAME GND\g
J 0
(-2790 585);
DISPLAY 0.659574 (-2790 585);
PAINT MONO (-2790 585);
DISPLAY INVISIBLE (-2790 585);
FORCEPROP 1 LAST VOLTAGE 0.0V
J 0
(-2845 482);
DISPLAY 0.340426 (-2845 482);
PAINT SKYBLUE (-2845 482);
DISPLAY INVISIBLE (-2845 482);
FORCEPROP 1 LAST SIZE 1B
J 0
(-2725 475);
DISPLAY 1.170213 (-2725 475);
PAINT AQUA (-2725 475);
DISPLAY INVISIBLE (-2725 475);
FORCEPROP 2 LAST CDS_LIB mstr_symbols
J 0
(-2800 525);
PAINT ORANGE (-2800 525);
DISPLAY INVISIBLE (-2800 525);
FORCEPROP 1 LAST PATH I276
J 0
(-2725 525);
DISPLAY 0.872340 (-2725 525);
PAINT AQUA (-2725 525);
DISPLAY INVISIBLE (-2725 525);
FORCEPROP 1 LAST BODY_TYPE PLUMBING
J 0
(-2845 482);
DISPLAY 0.340426 (-2845 482);
PAINT GREEN (-2845 482);
DISPLAY INVISIBLE (-2845 482);
FORCEPROP 1 LAST HDL_POWER GND
J 0
(-2800 675);
DISPLAY 1.170213 (-2800 675);
PAINT GREEN (-2800 675);
DISPLAY INVISIBLE (-2800 675);
FORCEADD GND..1
(-1075 475);
FORCEPROP 3 LASTPIN (-1075 525) SIG_NAME GND\g
J 0
(-1065 535);
DISPLAY 0.659574 (-1065 535);
PAINT MONO (-1065 535);
DISPLAY INVISIBLE (-1065 535);
FORCEPROP 1 LAST VOLTAGE 0.0V
J 0
(-1120 432);
DISPLAY 0.340426 (-1120 432);
PAINT SKYBLUE (-1120 432);
DISPLAY INVISIBLE (-1120 432);
FORCEPROP 1 LAST SIZE 1B
J 0
(-1000 425);
DISPLAY 1.170213 (-1000 425);
PAINT AQUA (-1000 425);
DISPLAY INVISIBLE (-1000 425);
FORCEPROP 2 LAST CDS_LIB mstr_symbols
J 0
(-1075 475);
PAINT ORANGE (-1075 475);
DISPLAY INVISIBLE (-1075 475);
FORCEPROP 1 LAST PATH I277
J 0
(-1000 475);
DISPLAY 0.872340 (-1000 475);
PAINT AQUA (-1000 475);
DISPLAY INVISIBLE (-1000 475);
FORCEPROP 1 LAST BODY_TYPE PLUMBING
J 0
(-1120 432);
DISPLAY 0.340426 (-1120 432);
PAINT GREEN (-1120 432);
DISPLAY INVISIBLE (-1120 432);
FORCEPROP 1 LAST HDL_POWER GND
J 0
(-1075 625);
DISPLAY 1.170213 (-1075 625);
PAINT GREEN (-1075 625);
DISPLAY INVISIBLE (-1075 625);
FORCEADD GND..1
(-6025 550);
FORCEPROP 3 LASTPIN (-6025 600) SIG_NAME GND\g
J 0
(-6015 610);
DISPLAY 0.659574 (-6015 610);
PAINT MONO (-6015 610);
DISPLAY INVISIBLE (-6015 610);
FORCEPROP 1 LAST VOLTAGE 0.0V
J 0
(-6070 507);
DISPLAY 0.340426 (-6070 507);
PAINT SKYBLUE (-6070 507);
DISPLAY INVISIBLE (-6070 507);
FORCEPROP 1 LAST SIZE 1B
J 0
(-5950 500);
DISPLAY 1.170213 (-5950 500);
PAINT AQUA (-5950 500);
DISPLAY INVISIBLE (-5950 500);
FORCEPROP 2 LAST CDS_LIB mstr_symbols
J 0
(-6025 550);
PAINT ORANGE (-6025 550);
DISPLAY INVISIBLE (-6025 550);
FORCEPROP 1 LAST PATH I278
J 0
(-5950 550);
DISPLAY 0.872340 (-5950 550);
PAINT AQUA (-5950 550);
DISPLAY INVISIBLE (-5950 550);
FORCEPROP 1 LAST BODY_TYPE PLUMBING
J 0
(-6070 507);
DISPLAY 0.340426 (-6070 507);
PAINT GREEN (-6070 507);
DISPLAY INVISIBLE (-6070 507);
FORCEPROP 1 LAST HDL_POWER GND
J 0
(-6025 700);
DISPLAY 1.170213 (-6025 700);
PAINT GREEN (-6025 700);
DISPLAY INVISIBLE (-6025 700);
FORCEADD GND..1
(-4350 550);
FORCEPROP 3 LASTPIN (-4350 600) SIG_NAME GND\g
J 0
(-4340 610);
DISPLAY 0.659574 (-4340 610);
PAINT MONO (-4340 610);
DISPLAY INVISIBLE (-4340 610);
FORCEPROP 1 LAST VOLTAGE 0.0V
J 0
(-4395 507);
DISPLAY 0.340426 (-4395 507);
PAINT SKYBLUE (-4395 507);
DISPLAY INVISIBLE (-4395 507);
FORCEPROP 1 LAST SIZE 1B
J 0
(-4275 500);
DISPLAY 1.170213 (-4275 500);
PAINT AQUA (-4275 500);
DISPLAY INVISIBLE (-4275 500);
FORCEPROP 2 LAST CDS_LIB mstr_symbols
J 0
(-4350 550);
PAINT ORANGE (-4350 550);
DISPLAY INVISIBLE (-4350 550);
FORCEPROP 1 LAST PATH I279
J 0
(-4275 550);
DISPLAY 0.872340 (-4275 550);
PAINT AQUA (-4275 550);
DISPLAY INVISIBLE (-4275 550);
FORCEPROP 1 LAST BODY_TYPE PLUMBING
J 0
(-4395 507);
DISPLAY 0.340426 (-4395 507);
PAINT GREEN (-4395 507);
DISPLAY INVISIBLE (-4395 507);
FORCEPROP 1 LAST HDL_POWER GND
J 0
(-4350 700);
DISPLAY 1.170213 (-4350 700);
PAINT GREEN (-4350 700);
DISPLAY INVISIBLE (-4350 700);
FORCEADD GND..1
(-2625 500);
FORCEPROP 3 LASTPIN (-2625 550) SIG_NAME GND\g
J 0
(-2615 560);
DISPLAY 0.659574 (-2615 560);
PAINT MONO (-2615 560);
DISPLAY INVISIBLE (-2615 560);
FORCEPROP 1 LAST VOLTAGE 0.0V
J 0
(-2670 457);
DISPLAY 0.340426 (-2670 457);
PAINT SKYBLUE (-2670 457);
DISPLAY INVISIBLE (-2670 457);
FORCEPROP 1 LAST SIZE 1B
J 0
(-2550 450);
DISPLAY 1.170213 (-2550 450);
PAINT AQUA (-2550 450);
DISPLAY INVISIBLE (-2550 450);
FORCEPROP 2 LAST CDS_LIB mstr_symbols
J 0
(-2625 500);
PAINT ORANGE (-2625 500);
DISPLAY INVISIBLE (-2625 500);
FORCEPROP 1 LAST PATH I280
J 0
(-2550 500);
DISPLAY 0.872340 (-2550 500);
PAINT AQUA (-2550 500);
DISPLAY INVISIBLE (-2550 500);
FORCEPROP 1 LAST BODY_TYPE PLUMBING
J 0
(-2670 457);
DISPLAY 0.340426 (-2670 457);
PAINT GREEN (-2670 457);
DISPLAY INVISIBLE (-2670 457);
FORCEPROP 1 LAST HDL_POWER GND
J 0
(-2625 650);
DISPLAY 1.170213 (-2625 650);
PAINT GREEN (-2625 650);
DISPLAY INVISIBLE (-2625 650);
FORCEADD GND..1
(-925 475);
FORCEPROP 3 LASTPIN (-925 525) SIG_NAME GND\g
J 0
(-915 535);
DISPLAY 0.659574 (-915 535);
PAINT MONO (-915 535);
DISPLAY INVISIBLE (-915 535);
FORCEPROP 1 LAST VOLTAGE 0.0V
J 0
(-970 432);
DISPLAY 0.340426 (-970 432);
PAINT SKYBLUE (-970 432);
DISPLAY INVISIBLE (-970 432);
FORCEPROP 1 LAST SIZE 1B
J 0
(-850 425);
DISPLAY 1.170213 (-850 425);
PAINT AQUA (-850 425);
DISPLAY INVISIBLE (-850 425);
FORCEPROP 2 LAST CDS_LIB mstr_symbols
J 0
(-925 475);
PAINT ORANGE (-925 475);
DISPLAY INVISIBLE (-925 475);
FORCEPROP 1 LAST PATH I281
J 0
(-850 475);
DISPLAY 0.872340 (-850 475);
PAINT AQUA (-850 475);
DISPLAY INVISIBLE (-850 475);
FORCEPROP 1 LAST BODY_TYPE PLUMBING
J 0
(-970 432);
DISPLAY 0.340426 (-970 432);
PAINT GREEN (-970 432);
DISPLAY INVISIBLE (-970 432);
FORCEPROP 1 LAST HDL_POWER GND
J 0
(-925 625);
DISPLAY 1.170213 (-925 625);
PAINT GREEN (-925 625);
DISPLAY INVISIBLE (-925 625);
FORCEADD GND..1
(600 1650);
FORCEPROP 3 LASTPIN (600 1700) SIG_NAME GND\g
J 0
(610 1710);
DISPLAY 0.659574 (610 1710);
PAINT MONO (610 1710);
DISPLAY INVISIBLE (610 1710);
FORCEPROP 1 LAST VOLTAGE 0.0V
J 0
(555 1607);
DISPLAY 0.340426 (555 1607);
PAINT SKYBLUE (555 1607);
DISPLAY INVISIBLE (555 1607);
FORCEPROP 1 LAST SIZE 1B
J 0
(675 1600);
DISPLAY 1.170213 (675 1600);
PAINT AQUA (675 1600);
DISPLAY INVISIBLE (675 1600);
FORCEPROP 2 LAST CDS_LIB mstr_symbols
J 0
(600 1650);
PAINT ORANGE (600 1650);
DISPLAY INVISIBLE (600 1650);
FORCEPROP 1 LAST PATH I282
J 0
(675 1650);
DISPLAY 0.872340 (675 1650);
PAINT AQUA (675 1650);
DISPLAY INVISIBLE (675 1650);
FORCEPROP 1 LAST BODY_TYPE PLUMBING
J 0
(555 1607);
DISPLAY 0.340426 (555 1607);
PAINT GREEN (555 1607);
DISPLAY INVISIBLE (555 1607);
FORCEPROP 1 LAST HDL_POWER GND
J 0
(600 1800);
DISPLAY 1.170213 (600 1800);
PAINT GREEN (600 1800);
DISPLAY INVISIBLE (600 1800);
FORCEADD SKX_EXT_B..27
(-5275 2650);
FORCEPROP 2 LASTPIN (-5875 4650) $PN BG74
J 2
(-5885 4660);
DISPLAY 0.617021 (-5885 4660);
PAINT ORANGE (-5885 4660);
FORCEPROP 2 LASTPIN (-4675 1650) $PN CG62
J 0
(-4665 1660);
DISPLAY 0.617021 (-4665 1660);
PAINT ORANGE (-4665 1660);
FORCEPROP 1 LAST LOCATION U5D1
J 0
(-5825 4900);
DISPLAY 0.617021 (-5825 4900);
PAINT AQUA (-5825 4900);
FORCEPROP 1 LAST PART_NUMBER TBD
J 0
(-5825 500);
DISPLAY 0.617021 (-5825 500);
PAINT BLUE (-5825 500);
FORCEPROP 1 LAST MATERIAL IC
J 0
(-5825 4850);
DISPLAY 0.617021 (-5825 4850);
PAINT SKYBLUE (-5825 4850);
FORCEPROP 2 LASTPIN (-5875 4600) $PN BG76
J 2
(-5885 4610);
DISPLAY 0.617021 (-5885 4610);
PAINT ORANGE (-5885 4610);
FORCEPROP 2 LASTPIN (-5875 4550) $PN BG78
J 2
(-5885 4560);
DISPLAY 0.617021 (-5885 4560);
PAINT ORANGE (-5885 4560);
FORCEPROP 2 LASTPIN (-5875 4500) $PN BG80
J 2
(-5885 4510);
DISPLAY 0.617021 (-5885 4510);
PAINT ORANGE (-5885 4510);
FORCEPROP 2 LASTPIN (-5875 4450) $PN BG82
J 2
(-5885 4460);
DISPLAY 0.617021 (-5885 4460);
PAINT ORANGE (-5885 4460);
FORCEPROP 2 LASTPIN (-5875 4350) $PN BH9
J 2
(-5885 4360);
DISPLAY 0.617021 (-5885 4360);
PAINT ORANGE (-5885 4360);
FORCEPROP 2 LASTPIN (-5875 4250) $PN BH15
J 2
(-5885 4260);
DISPLAY 0.617021 (-5885 4260);
PAINT ORANGE (-5885 4260);
FORCEPROP 2 LASTPIN (-5875 4200) $PN BH21
J 2
(-5885 4210);
DISPLAY 0.617021 (-5885 4210);
PAINT ORANGE (-5885 4210);
FORCEPROP 2 LASTPIN (-5875 4150) $PN BJ4
J 2
(-5885 4160);
DISPLAY 0.617021 (-5885 4160);
PAINT ORANGE (-5885 4160);
FORCEPROP 2 LASTPIN (-5875 4100) $PN BJ6
J 2
(-5885 4110);
DISPLAY 0.617021 (-5885 4110);
PAINT ORANGE (-5885 4110);
FORCEPROP 2 LASTPIN (-5875 4050) $PN BK3
J 2
(-5885 4060);
DISPLAY 0.617021 (-5885 4060);
PAINT ORANGE (-5885 4060);
FORCEPROP 2 LASTPIN (-5875 4000) $PN BK7
J 2
(-5885 4010);
DISPLAY 0.617021 (-5885 4010);
PAINT ORANGE (-5885 4010);
FORCEPROP 2 LASTPIN (-5875 3950) $PN BK11
J 2
(-5885 3960);
DISPLAY 0.617021 (-5885 3960);
PAINT ORANGE (-5885 3960);
FORCEPROP 2 LASTPIN (-5875 3900) $PN BK19
J 2
(-5885 3910);
DISPLAY 0.617021 (-5885 3910);
PAINT ORANGE (-5885 3910);
FORCEPROP 2 LASTPIN (-5875 3850) $PN BL6
J 2
(-5885 3860);
DISPLAY 0.617021 (-5885 3860);
PAINT ORANGE (-5885 3860);
FORCEPROP 2 LASTPIN (-5875 3800) $PN BL10
J 2
(-5885 3810);
DISPLAY 0.617021 (-5885 3810);
PAINT ORANGE (-5885 3810);
FORCEPROP 2 LASTPIN (-5875 3750) $PN BL12
J 2
(-5885 3760);
DISPLAY 0.617021 (-5885 3760);
PAINT ORANGE (-5885 3760);
FORCEPROP 2 LASTPIN (-5875 3700) $PN P61
J 2
(-5885 3710);
DISPLAY 0.617021 (-5885 3710);
PAINT ORANGE (-5885 3710);
FORCEPROP 2 LASTPIN (-5875 3650) $PN BL22
J 2
(-5885 3660);
DISPLAY 0.617021 (-5885 3660);
PAINT ORANGE (-5885 3660);
FORCEPROP 2 LASTPIN (-5875 3600) $PN BL24
J 2
(-5885 3610);
DISPLAY 0.617021 (-5885 3610);
PAINT ORANGE (-5885 3610);
FORCEPROP 2 LASTPIN (-5875 3550) $PN BL64
J 2
(-5885 3560);
DISPLAY 0.617021 (-5885 3560);
PAINT ORANGE (-5885 3560);
FORCEPROP 2 LASTPIN (-5875 3500) $PN BL66
J 2
(-5885 3510);
DISPLAY 0.617021 (-5885 3510);
PAINT ORANGE (-5885 3510);
FORCEPROP 2 LASTPIN (-5875 3450) $PN BL68
J 2
(-5885 3460);
DISPLAY 0.617021 (-5885 3460);
PAINT ORANGE (-5885 3460);
FORCEPROP 2 LASTPIN (-5875 3400) $PN BL70
J 2
(-5885 3410);
DISPLAY 0.617021 (-5885 3410);
PAINT ORANGE (-5885 3410);
FORCEPROP 2 LASTPIN (-5875 3350) $PN BL72
J 2
(-5885 3360);
DISPLAY 0.617021 (-5885 3360);
PAINT ORANGE (-5885 3360);
FORCEPROP 2 LASTPIN (-5875 3300) $PN BL74
J 2
(-5885 3310);
DISPLAY 0.617021 (-5885 3310);
PAINT ORANGE (-5885 3310);
FORCEPROP 2 LASTPIN (-5875 3250) $PN BL76
J 2
(-5885 3260);
DISPLAY 0.617021 (-5885 3260);
PAINT ORANGE (-5885 3260);
FORCEPROP 2 LASTPIN (-5875 3200) $PN BL78
J 2
(-5885 3210);
DISPLAY 0.617021 (-5885 3210);
PAINT ORANGE (-5885 3210);
FORCEPROP 2 LASTPIN (-5875 3150) $PN BL80
J 2
(-5885 3160);
DISPLAY 0.617021 (-5885 3160);
PAINT ORANGE (-5885 3160);
FORCEPROP 2 LASTPIN (-5875 3100) $PN BL82
J 2
(-5885 3110);
DISPLAY 0.617021 (-5885 3110);
PAINT ORANGE (-5885 3110);
FORCEPROP 2 LASTPIN (-5875 3050) $PN BM9
J 2
(-5885 3060);
DISPLAY 0.617021 (-5885 3060);
PAINT ORANGE (-5885 3060);
FORCEPROP 2 LASTPIN (-5875 3000) $PN BM13
J 2
(-5885 3010);
DISPLAY 0.617021 (-5885 3010);
PAINT ORANGE (-5885 3010);
FORCEPROP 2 LASTPIN (-5875 2950) $PN BM15
J 2
(-5885 2960);
DISPLAY 0.617021 (-5885 2960);
PAINT ORANGE (-5885 2960);
FORCEPROP 2 LASTPIN (-5875 2900) $PN P59
J 2
(-5885 2910);
DISPLAY 0.617021 (-5885 2910);
PAINT ORANGE (-5885 2910);
FORCEPROP 2 LASTPIN (-5875 2850) $PN BM25
J 2
(-5885 2860);
DISPLAY 0.617021 (-5885 2860);
PAINT ORANGE (-5885 2860);
FORCEPROP 2 LASTPIN (-5875 2800) $PN BN6
J 2
(-5885 2810);
DISPLAY 0.617021 (-5885 2810);
PAINT ORANGE (-5885 2810);
FORCEPROP 2 LASTPIN (-5875 2750) $PN BN10
J 2
(-5885 2760);
DISPLAY 0.617021 (-5885 2760);
PAINT ORANGE (-5885 2760);
FORCEPROP 2 LASTPIN (-5875 2700) $PN BN20
J 2
(-5885 2710);
DISPLAY 0.617021 (-5885 2710);
PAINT ORANGE (-5885 2710);
FORCEPROP 2 LASTPIN (-5875 2650) $PN BN26
J 2
(-5885 2660);
DISPLAY 0.617021 (-5885 2660);
PAINT ORANGE (-5885 2660);
FORCEPROP 2 LASTPIN (-5875 2600) $PN BP3
J 2
(-5885 2610);
DISPLAY 0.617021 (-5885 2610);
PAINT ORANGE (-5885 2610);
FORCEPROP 2 LASTPIN (-5875 2550) $PN BP27
J 2
(-5885 2560);
DISPLAY 0.617021 (-5885 2560);
PAINT ORANGE (-5885 2560);
FORCEPROP 2 LASTPIN (-5875 2500) $PN BR6
J 2
(-5885 2510);
DISPLAY 0.617021 (-5885 2510);
PAINT ORANGE (-5885 2510);
FORCEPROP 2 LASTPIN (-5875 2450) $PN BR10
J 2
(-5885 2460);
DISPLAY 0.617021 (-5885 2460);
PAINT ORANGE (-5885 2460);
FORCEPROP 2 LASTPIN (-5875 2400) $PN BR16
J 2
(-5885 2410);
DISPLAY 0.617021 (-5885 2410);
PAINT ORANGE (-5885 2410);
FORCEPROP 2 LASTPIN (-5875 2350) $PN P57
J 2
(-5885 2360);
DISPLAY 0.617021 (-5885 2360);
PAINT ORANGE (-5885 2360);
FORCEPROP 2 LASTPIN (-5875 2300) $PN BR64
J 2
(-5885 2310);
DISPLAY 0.617021 (-5885 2310);
PAINT ORANGE (-5885 2310);
FORCEPROP 2 LASTPIN (-5875 2250) $PN BR66
J 2
(-5885 2260);
DISPLAY 0.617021 (-5885 2260);
PAINT ORANGE (-5885 2260);
FORCEPROP 2 LASTPIN (-5875 2200) $PN BR68
J 2
(-5885 2210);
DISPLAY 0.617021 (-5885 2210);
PAINT ORANGE (-5885 2210);
FORCEPROP 2 LASTPIN (-5875 2150) $PN BR70
J 2
(-5885 2160);
DISPLAY 0.617021 (-5885 2160);
PAINT ORANGE (-5885 2160);
FORCEPROP 2 LASTPIN (-5875 2100) $PN BR72
J 2
(-5885 2110);
DISPLAY 0.617021 (-5885 2110);
PAINT ORANGE (-5885 2110);
FORCEPROP 2 LASTPIN (-5875 2050) $PN BR74
J 2
(-5885 2060);
DISPLAY 0.617021 (-5885 2060);
PAINT ORANGE (-5885 2060);
FORCEPROP 2 LASTPIN (-5875 2000) $PN BR76
J 2
(-5885 2010);
DISPLAY 0.617021 (-5885 2010);
PAINT ORANGE (-5885 2010);
FORCEPROP 2 LASTPIN (-5875 1950) $PN BR78
J 2
(-5885 1960);
DISPLAY 0.617021 (-5885 1960);
PAINT ORANGE (-5885 1960);
FORCEPROP 2 LASTPIN (-5875 1900) $PN BR80
J 2
(-5885 1910);
DISPLAY 0.617021 (-5885 1910);
PAINT ORANGE (-5885 1910);
FORCEPROP 2 LASTPIN (-5875 1850) $PN BR82
J 2
(-5885 1860);
DISPLAY 0.617021 (-5885 1860);
PAINT ORANGE (-5885 1860);
FORCEPROP 2 LASTPIN (-5875 1800) $PN BT3
J 2
(-5885 1810);
DISPLAY 0.617021 (-5885 1810);
PAINT ORANGE (-5885 1810);
FORCEPROP 2 LASTPIN (-5875 1750) $PN BT5
J 2
(-5885 1760);
DISPLAY 0.617021 (-5885 1760);
PAINT ORANGE (-5885 1760);
FORCEPROP 2 LASTPIN (-5875 1700) $PN BT21
J 2
(-5885 1710);
DISPLAY 0.617021 (-5885 1710);
PAINT ORANGE (-5885 1710);
FORCEPROP 2 LASTPIN (-5875 1650) $PN BT23
J 2
(-5885 1660);
DISPLAY 0.617021 (-5885 1660);
PAINT ORANGE (-5885 1660);
FORCEPROP 2 LASTPIN (-5875 1600) $PN BT25
J 2
(-5885 1610);
DISPLAY 0.617021 (-5885 1610);
PAINT ORANGE (-5885 1610);
FORCEPROP 2 LASTPIN (-5875 1550) $PN BU8
J 2
(-5885 1560);
DISPLAY 0.617021 (-5885 1560);
PAINT ORANGE (-5885 1560);
FORCEPROP 2 LASTPIN (-5875 1500) $PN BV5
J 2
(-5885 1510);
DISPLAY 0.617021 (-5885 1510);
PAINT ORANGE (-5885 1510);
FORCEPROP 2 LASTPIN (-5875 1450) $PN BU10
J 2
(-5885 1460);
DISPLAY 0.617021 (-5885 1460);
PAINT ORANGE (-5885 1460);
FORCEPROP 2 LASTPIN (-5875 1400) $PN BV17
J 2
(-5885 1410);
DISPLAY 0.617021 (-5885 1410);
PAINT ORANGE (-5885 1410);
FORCEPROP 2 LASTPIN (-5875 1350) $PN BV25
J 2
(-5885 1360);
DISPLAY 0.617021 (-5885 1360);
PAINT ORANGE (-5885 1360);
FORCEPROP 2 LASTPIN (-5875 1300) $PN BW6
J 2
(-5885 1310);
DISPLAY 0.617021 (-5885 1310);
PAINT ORANGE (-5885 1310);
FORCEPROP 2 LASTPIN (-5875 1250) $PN P55
J 2
(-5885 1260);
DISPLAY 0.617021 (-5885 1260);
PAINT ORANGE (-5885 1260);
FORCEPROP 2 LASTPIN (-5875 1200) $PN BW12
J 2
(-5885 1210);
DISPLAY 0.617021 (-5885 1210);
PAINT ORANGE (-5885 1210);
FORCEPROP 2 LASTPIN (-5875 1150) $PN BW14
J 2
(-5885 1160);
DISPLAY 0.617021 (-5885 1160);
PAINT ORANGE (-5885 1160);
FORCEPROP 2 LASTPIN (-5875 1100) $PN BW16
J 2
(-5885 1110);
DISPLAY 0.617021 (-5885 1110);
PAINT ORANGE (-5885 1110);
FORCEPROP 2 LASTPIN (-5875 1050) $PN BW18
J 2
(-5885 1060);
DISPLAY 0.617021 (-5885 1060);
PAINT ORANGE (-5885 1060);
FORCEPROP 2 LASTPIN (-5875 1000) $PN BW26
J 2
(-5885 1010);
DISPLAY 0.617021 (-5885 1010);
PAINT ORANGE (-5885 1010);
FORCEPROP 2 LASTPIN (-5875 950) $PN BW72
J 2
(-5885 960);
DISPLAY 0.617021 (-5885 960);
PAINT ORANGE (-5885 960);
FORCEPROP 2 LASTPIN (-5875 900) $PN BW74
J 2
(-5885 910);
DISPLAY 0.617021 (-5885 910);
PAINT ORANGE (-5885 910);
FORCEPROP 2 LASTPIN (-5875 850) $PN BW76
J 2
(-5885 860);
DISPLAY 0.617021 (-5885 860);
PAINT ORANGE (-5885 860);
FORCEPROP 2 LASTPIN (-5875 800) $PN BW78
J 2
(-5885 810);
DISPLAY 0.617021 (-5885 810);
PAINT ORANGE (-5885 810);
FORCEPROP 2 LASTPIN (-5875 750) $PN BW80
J 2
(-5885 760);
DISPLAY 0.617021 (-5885 760);
PAINT ORANGE (-5885 760);
FORCEPROP 2 LASTPIN (-5875 700) $PN BW82
J 2
(-5885 710);
DISPLAY 0.617021 (-5885 710);
PAINT ORANGE (-5885 710);
FORCEPROP 2 LASTPIN (-4675 4650) $PN BY11
J 0
(-4665 4660);
DISPLAY 0.617021 (-4665 4660);
PAINT ORANGE (-4665 4660);
FORCEPROP 2 LASTPIN (-4675 4600) $PN BY13
J 0
(-4665 4610);
DISPLAY 0.617021 (-4665 4610);
PAINT ORANGE (-4665 4610);
FORCEPROP 2 LASTPIN (-4675 4500) $PN BY63
J 0
(-4665 4510);
DISPLAY 0.617021 (-4665 4510);
PAINT ORANGE (-4665 4510);
FORCEPROP 2 LASTPIN (-4675 4450) $PN BY65
J 0
(-4665 4460);
DISPLAY 0.617021 (-4665 4460);
PAINT ORANGE (-4665 4460);
FORCEPROP 2 LASTPIN (-4675 4400) $PN BY67
J 0
(-4665 4410);
DISPLAY 0.617021 (-4665 4410);
PAINT ORANGE (-4665 4410);
FORCEPROP 2 LASTPIN (-4675 4350) $PN BY69
J 0
(-4665 4360);
DISPLAY 0.617021 (-4665 4360);
PAINT ORANGE (-4665 4360);
FORCEPROP 2 LASTPIN (-4675 4300) $PN BY71
J 0
(-4665 4310);
DISPLAY 0.617021 (-4665 4310);
PAINT ORANGE (-4665 4310);
FORCEPROP 2 LASTPIN (-4675 4250) $PN CA2
J 0
(-4665 4260);
DISPLAY 0.617021 (-4665 4260);
PAINT ORANGE (-4665 4260);
FORCEPROP 2 LASTPIN (-4675 4200) $PN CA6
J 0
(-4665 4210);
DISPLAY 0.617021 (-4665 4210);
PAINT ORANGE (-4665 4210);
FORCEPROP 2 LASTPIN (-4675 4150) $PN CA8
J 0
(-4665 4160);
DISPLAY 0.617021 (-4665 4160);
PAINT ORANGE (-4665 4160);
FORCEPROP 2 LASTPIN (-4675 4050) $PN CA14
J 0
(-4665 4060);
DISPLAY 0.617021 (-4665 4060);
PAINT ORANGE (-4665 4060);
FORCEPROP 2 LASTPIN (-4675 4000) $PN CA18
J 0
(-4665 4010);
DISPLAY 0.617021 (-4665 4010);
PAINT ORANGE (-4665 4010);
FORCEPROP 2 LASTPIN (-4675 3950) $PN CA26
J 0
(-4665 3960);
DISPLAY 0.617021 (-4665 3960);
PAINT ORANGE (-4665 3960);
FORCEPROP 2 LASTPIN (-4675 3900) $PN CA64
J 0
(-4665 3910);
DISPLAY 0.617021 (-4665 3910);
PAINT ORANGE (-4665 3910);
FORCEPROP 2 LASTPIN (-4675 3850) $PN CA66
J 0
(-4665 3860);
DISPLAY 0.617021 (-4665 3860);
PAINT ORANGE (-4665 3860);
FORCEPROP 2 LASTPIN (-4675 3800) $PN CA68
J 0
(-4665 3810);
DISPLAY 0.617021 (-4665 3810);
PAINT ORANGE (-4665 3810);
FORCEPROP 2 LASTPIN (-4675 3750) $PN CA70
J 0
(-4665 3760);
DISPLAY 0.617021 (-4665 3760);
PAINT ORANGE (-4665 3760);
FORCEPROP 2 LASTPIN (-4675 3700) $PN CB7
J 0
(-4665 3710);
DISPLAY 0.617021 (-4665 3710);
PAINT ORANGE (-4665 3710);
FORCEPROP 2 LASTPIN (-4675 3650) $PN CB9
J 0
(-4665 3660);
DISPLAY 0.617021 (-4665 3660);
PAINT ORANGE (-4665 3660);
FORCEPROP 2 LASTPIN (-4675 3600) $PN CB27
J 0
(-4665 3610);
DISPLAY 0.617021 (-4665 3610);
PAINT ORANGE (-4665 3610);
FORCEPROP 2 LASTPIN (-4675 3550) $PN CB63
J 0
(-4665 3560);
DISPLAY 0.617021 (-4665 3560);
PAINT ORANGE (-4665 3560);
FORCEPROP 2 LASTPIN (-4675 3500) $PN CB71
J 0
(-4665 3510);
DISPLAY 0.617021 (-4665 3510);
PAINT ORANGE (-4665 3510);
FORCEPROP 2 LASTPIN (-4675 3450) $PN CC4
J 0
(-4665 3460);
DISPLAY 0.617021 (-4665 3460);
PAINT ORANGE (-4665 3460);
FORCEPROP 2 LASTPIN (-4675 3400) $PN CC16
J 0
(-4665 3410);
DISPLAY 0.617021 (-4665 3410);
PAINT ORANGE (-4665 3410);
FORCEPROP 2 LASTPIN (-4675 3350) $PN CC18
J 0
(-4665 3360);
DISPLAY 0.617021 (-4665 3360);
PAINT ORANGE (-4665 3360);
FORCEPROP 2 LASTPIN (-4675 3300) $PN CC24
J 0
(-4665 3310);
DISPLAY 0.617021 (-4665 3310);
PAINT ORANGE (-4665 3310);
FORCEPROP 2 LASTPIN (-4675 3250) $PN CC64
J 0
(-4665 3260);
DISPLAY 0.617021 (-4665 3260);
PAINT ORANGE (-4665 3260);
FORCEPROP 2 LASTPIN (-4675 3200) $PN CC72
J 0
(-4665 3210);
DISPLAY 0.617021 (-4665 3210);
PAINT ORANGE (-4665 3210);
FORCEPROP 2 LASTPIN (-4675 3150) $PN CC74
J 0
(-4665 3160);
DISPLAY 0.617021 (-4665 3160);
PAINT ORANGE (-4665 3160);
FORCEPROP 2 LASTPIN (-4675 3100) $PN CC76
J 0
(-4665 3110);
DISPLAY 0.617021 (-4665 3110);
PAINT ORANGE (-4665 3110);
FORCEPROP 2 LASTPIN (-4675 3050) $PN CC78
J 0
(-4665 3060);
DISPLAY 0.617021 (-4665 3060);
PAINT ORANGE (-4665 3060);
FORCEPROP 2 LASTPIN (-4675 3000) $PN CC80
J 0
(-4665 3010);
DISPLAY 0.617021 (-4665 3010);
PAINT ORANGE (-4665 3010);
FORCEPROP 2 LASTPIN (-4675 2950) $PN CC82
J 0
(-4665 2960);
DISPLAY 0.617021 (-4665 2960);
PAINT ORANGE (-4665 2960);
FORCEPROP 2 LASTPIN (-4675 2900) $PN CD5
J 0
(-4665 2910);
DISPLAY 0.617021 (-4665 2910);
PAINT ORANGE (-4665 2910);
FORCEPROP 2 LASTPIN (-4675 2850) $PN CD13
J 0
(-4665 2860);
DISPLAY 0.617021 (-4665 2860);
PAINT ORANGE (-4665 2860);
FORCEPROP 2 LASTPIN (-4675 2750) $PN CD73
J 0
(-4665 2760);
DISPLAY 0.617021 (-4665 2760);
PAINT ORANGE (-4665 2760);
FORCEPROP 2 LASTPIN (-4675 2700) $PN CD75
J 0
(-4665 2710);
DISPLAY 0.617021 (-4665 2710);
PAINT ORANGE (-4665 2710);
FORCEPROP 2 LASTPIN (-4675 2650) $PN CD77
J 0
(-4665 2660);
DISPLAY 0.617021 (-4665 2660);
PAINT ORANGE (-4665 2660);
FORCEPROP 2 LASTPIN (-4675 2600) $PN CD79
J 0
(-4665 2610);
DISPLAY 0.617021 (-4665 2610);
PAINT ORANGE (-4665 2610);
FORCEPROP 2 LASTPIN (-4675 2550) $PN CD81
J 0
(-4665 2560);
DISPLAY 0.617021 (-4665 2560);
PAINT ORANGE (-4665 2560);
FORCEPROP 2 LASTPIN (-4675 2500) $PN CE10
J 0
(-4665 2510);
DISPLAY 0.617021 (-4665 2510);
PAINT ORANGE (-4665 2510);
FORCEPROP 2 LASTPIN (-4675 2450) $PN CE14
J 0
(-4665 2460);
DISPLAY 0.617021 (-4665 2460);
PAINT ORANGE (-4665 2460);
FORCEPROP 2 LASTPIN (-4675 2400) $PN CE20
J 0
(-4665 2410);
DISPLAY 0.617021 (-4665 2410);
PAINT ORANGE (-4665 2410);
FORCEPROP 2 LASTPIN (-4675 2350) $PN CE26
J 0
(-4665 2360);
DISPLAY 0.617021 (-4665 2360);
PAINT ORANGE (-4665 2360);
FORCEPROP 2 LASTPIN (-4675 2300) $PN CE62
J 0
(-4665 2310);
DISPLAY 0.617021 (-4665 2310);
PAINT ORANGE (-4665 2310);
FORCEPROP 2 LASTPIN (-4675 2250) $PN CE70
J 0
(-4665 2260);
DISPLAY 0.617021 (-4665 2260);
PAINT ORANGE (-4665 2260);
FORCEPROP 2 LASTPIN (-4675 2200) $PN CE82
J 0
(-4665 2210);
DISPLAY 0.617021 (-4665 2210);
PAINT ORANGE (-4665 2210);
FORCEPROP 2 LASTPIN (-4675 2150) $PN P53
J 0
(-4665 2160);
DISPLAY 0.617021 (-4665 2160);
PAINT ORANGE (-4665 2160);
FORCEPROP 2 LASTPIN (-4675 2100) $PN CF9
J 0
(-4665 2110);
DISPLAY 0.617021 (-4665 2110);
PAINT ORANGE (-4665 2110);
FORCEPROP 2 LASTPIN (-4675 2050) $PN CF63
J 0
(-4665 2060);
DISPLAY 0.617021 (-4665 2060);
PAINT ORANGE (-4665 2060);
FORCEPROP 2 LASTPIN (-4675 2000) $PN CF69
J 0
(-4665 2010);
DISPLAY 0.617021 (-4665 2010);
PAINT ORANGE (-4665 2010);
FORCEPROP 2 LASTPIN (-4675 1950) $PN CF71
J 0
(-4665 1960);
DISPLAY 0.617021 (-4665 1960);
PAINT ORANGE (-4665 1960);
FORCEPROP 2 LASTPIN (-4675 1900) $PN CF77
J 0
(-4665 1910);
DISPLAY 0.617021 (-4665 1910);
PAINT ORANGE (-4665 1910);
FORCEPROP 2 LASTPIN (-4675 1850) $PN CF83
J 0
(-4665 1860);
DISPLAY 0.617021 (-4665 1860);
PAINT ORANGE (-4665 1860);
FORCEPROP 2 LASTPIN (-4675 1800) $PN P51
J 0
(-4665 1810);
DISPLAY 0.617021 (-4665 1810);
PAINT ORANGE (-4665 1810);
FORCEPROP 2 LASTPIN (-4675 1750) $PN CG18
J 0
(-4665 1760);
DISPLAY 0.617021 (-4665 1760);
PAINT ORANGE (-4665 1760);
FORCEPROP 2 LASTPIN (-4675 1700) $PN CG22
J 0
(-4665 1710);
DISPLAY 0.617021 (-4665 1710);
PAINT ORANGE (-4665 1710);
FORCEPROP 2 LASTPIN (-4675 1600) $PN CG68
J 0
(-4665 1610);
DISPLAY 0.617021 (-4665 1610);
PAINT ORANGE (-4665 1610);
FORCEPROP 2 LASTPIN (-4675 1550) $PN CG72
J 0
(-4665 1560);
DISPLAY 0.617021 (-4665 1560);
PAINT ORANGE (-4665 1560);
FORCEPROP 2 LASTPIN (-4675 1500) $PN CG80
J 0
(-4665 1510);
DISPLAY 0.617021 (-4665 1510);
PAINT ORANGE (-4665 1510);
FORCEPROP 2 LASTPIN (-4675 1450) $PN CH1
J 0
(-4665 1460);
DISPLAY 0.617021 (-4665 1460);
PAINT ORANGE (-4665 1460);
FORCEPROP 2 LASTPIN (-4675 1400) $PN CH3
J 0
(-4665 1410);
DISPLAY 0.617021 (-4665 1410);
PAINT ORANGE (-4665 1410);
FORCEPROP 2 LASTPIN (-4675 1350) $PN CH15
J 0
(-4665 1360);
DISPLAY 0.617021 (-4665 1360);
PAINT ORANGE (-4665 1360);
FORCEPROP 2 LASTPIN (-4675 1300) $PN CH19
J 0
(-4665 1310);
DISPLAY 0.617021 (-4665 1310);
PAINT ORANGE (-4665 1310);
FORCEPROP 2 LASTPIN (-4675 1250) $PN CH63
J 0
(-4665 1260);
DISPLAY 0.617021 (-4665 1260);
PAINT ORANGE (-4665 1260);
FORCEPROP 2 LASTPIN (-4675 1200) $PN CH67
J 0
(-4665 1210);
DISPLAY 0.617021 (-4665 1210);
PAINT ORANGE (-4665 1210);
FORCEPROP 2 LASTPIN (-4675 1150) $PN CH73
J 0
(-4665 1160);
DISPLAY 0.617021 (-4665 1160);
PAINT ORANGE (-4665 1160);
FORCEPROP 2 LASTPIN (-4675 1100) $PN CH79
J 0
(-4665 1110);
DISPLAY 0.617021 (-4665 1110);
PAINT ORANGE (-4665 1110);
FORCEPROP 2 LASTPIN (-4675 1050) $PN CH81
J 0
(-4665 1060);
DISPLAY 0.617021 (-4665 1060);
PAINT ORANGE (-4665 1060);
FORCEPROP 2 LASTPIN (-4675 1000) $PN CH83
J 0
(-4665 1010);
DISPLAY 0.617021 (-4665 1010);
PAINT ORANGE (-4665 1010);
FORCEPROP 2 LASTPIN (-4675 950) $PN CJ2
J 0
(-4665 960);
DISPLAY 0.617021 (-4665 960);
PAINT ORANGE (-4665 960);
FORCEPROP 2 LASTPIN (-4675 900) $PN CJ6
J 0
(-4665 910);
DISPLAY 0.617021 (-4665 910);
PAINT ORANGE (-4665 910);
FORCEPROP 2 LASTPIN (-4675 850) $PN CJ8
J 0
(-4665 860);
DISPLAY 0.617021 (-4665 860);
PAINT ORANGE (-4665 860);
FORCEPROP 2 LASTPIN (-4675 800) $PN CJ10
J 0
(-4665 810);
DISPLAY 0.617021 (-4665 810);
PAINT ORANGE (-4665 810);
FORCEPROP 2 LASTPIN (-4675 750) $PN CJ12
J 0
(-4665 760);
DISPLAY 0.617021 (-4665 760);
PAINT ORANGE (-4665 760);
FORCEPROP 2 LASTPIN (-4675 700) $PN P49
J 0
(-4665 710);
DISPLAY 0.617021 (-4665 710);
PAINT ORANGE (-4665 710);
FORCEPROP 2 LASTPIN (-4675 2800) $PN CD63
J 0
(-4665 2810);
DISPLAY 0.617021 (-4665 2810);
PAINT ORANGE (-4665 2810);
FORCEPROP 2 LASTPIN (-5875 4400) $PN BH7
J 2
(-5885 4410);
DISPLAY 0.617021 (-5885 4410);
PAINT ORANGE (-5885 4410);
FORCEPROP 2 LASTPIN (-4675 4550) $PN BY23
J 0
(-4665 4560);
DISPLAY 0.617021 (-4665 4560);
PAINT ORANGE (-4665 4560);
FORCEPROP 2 LASTPIN (-5875 4300) $PN BH11
J 2
(-5885 4310);
DISPLAY 0.617021 (-5885 4310);
PAINT ORANGE (-5885 4310);
FORCEPROP 2 LASTPIN (-4675 4100) $PN CA10
J 0
(-4665 4110);
DISPLAY 0.617021 (-4665 4110);
PAINT ORANGE (-4665 4110);
FORCEPROP 1 LAST PACK_TYPE BGA1
J 0
(-5825 4950);
PAINT SKYBLUE (-5825 4950);
DISPLAY INVISIBLE (-5825 4950);
FORCEPROP 2 LAST CDS_LIB chpset_lib
J 0
(-5275 2650);
PAINT ORANGE (-5275 2650);
DISPLAY INVISIBLE (-5275 2650);
FORCEPROP 2 LAST SEC_TYPE BGA1
J 0
(-5825 4950);
DISPLAY 1.021277 (-5825 4950);
PAINT ORANGE (-5825 4950);
DISPLAY INVISIBLE (-5825 4950);
FORCEPROP 2 LAST SEC 27
J 0
(-5825 4950);
DISPLAY 0.680851 (-5825 4950);
PAINT MONO (-5825 4950);
DISPLAY INVISIBLE (-5825 4950);
FORCEPROP 2 LAST CDS_LOCATION U5D1
J 0
(-5825 4900);
DISPLAY 0.617021 (-5825 4900);
PAINT AQUA (-5825 4900);
DISPLAY INVISIBLE (-5825 4900);
FORCEPROP 1 LAST PATH I283
J 0
(-5275 4850);
PAINT GREEN (-5275 4850);
DISPLAY INVISIBLE (-5275 4850);
FORCEPROP 0 LAST ROOM CPU0
J 0
(-5825 5000);
DISPLAY 1.021277 (-5825 5000);
PAINT ORANGE (-5825 5000);
DISPLAY INVISIBLE (-5825 5000);
FORCEADD SKX_EXT_B..28
(-3575 2650);
FORCEPROP 2 LASTPIN (-4175 4450) $PN CJ78
J 2
(-4185 4460);
DISPLAY 0.617021 (-4185 4460);
PAINT ORANGE (-4185 4460);
FORCEPROP 1 LAST LOCATION U5D1
J 0
(-4125 4900);
DISPLAY 0.617021 (-4125 4900);
PAINT AQUA (-4125 4900);
FORCEPROP 1 LAST PART_NUMBER TBD
J 0
(-4125 500);
DISPLAY 0.617021 (-4125 500);
PAINT BLUE (-4125 500);
FORCEPROP 1 LAST MATERIAL IC
J 0
(-4125 4850);
DISPLAY 0.617021 (-4125 4850);
PAINT SKYBLUE (-4125 4850);
FORCEPROP 2 LASTPIN (-4175 4650) $PN P47
J 2
(-4185 4660);
DISPLAY 0.617021 (-4185 4660);
PAINT ORANGE (-4185 4660);
FORCEPROP 2 LASTPIN (-4175 4600) $PN CJ62
J 2
(-4185 4610);
DISPLAY 0.617021 (-4185 4610);
PAINT ORANGE (-4185 4610);
FORCEPROP 2 LASTPIN (-4175 4550) $PN CJ74
J 2
(-4185 4560);
DISPLAY 0.617021 (-4185 4560);
PAINT ORANGE (-4185 4560);
FORCEPROP 2 LASTPIN (-4175 4500) $PN CJ76
J 2
(-4185 4510);
DISPLAY 0.617021 (-4185 4510);
PAINT ORANGE (-4185 4510);
FORCEPROP 2 LASTPIN (-4175 4400) $PN CJ82
J 2
(-4185 4410);
DISPLAY 0.617021 (-4185 4410);
PAINT ORANGE (-4185 4410);
FORCEPROP 2 LASTPIN (-4175 4350) $PN CJ84
J 2
(-4185 4360);
DISPLAY 0.617021 (-4185 4360);
PAINT ORANGE (-4185 4360);
FORCEPROP 2 LASTPIN (-4175 4300) $PN CJ86
J 2
(-4185 4310);
DISPLAY 0.617021 (-4185 4310);
PAINT ORANGE (-4185 4310);
FORCEPROP 2 LASTPIN (-4175 4250) $PN CK11
J 2
(-4185 4260);
DISPLAY 0.617021 (-4185 4260);
PAINT ORANGE (-4185 4260);
FORCEPROP 2 LASTPIN (-4175 4200) $PN CK15
J 2
(-4185 4210);
DISPLAY 0.617021 (-4185 4210);
PAINT ORANGE (-4185 4210);
FORCEPROP 2 LASTPIN (-4175 4150) $PN CK21
J 2
(-4185 4160);
DISPLAY 0.617021 (-4185 4160);
PAINT ORANGE (-4185 4160);
FORCEPROP 2 LASTPIN (-4175 4100) $PN CK27
J 2
(-4185 4110);
DISPLAY 0.617021 (-4185 4110);
PAINT ORANGE (-4185 4110);
FORCEPROP 2 LASTPIN (-4175 4050) $PN CK63
J 2
(-4185 4060);
DISPLAY 0.617021 (-4185 4060);
PAINT ORANGE (-4185 4060);
FORCEPROP 2 LASTPIN (-4175 4000) $PN CK65
J 2
(-4185 4010);
DISPLAY 0.617021 (-4185 4010);
PAINT ORANGE (-4185 4010);
FORCEPROP 2 LASTPIN (-4175 3950) $PN CK67
J 2
(-4185 3960);
DISPLAY 0.617021 (-4185 3960);
PAINT ORANGE (-4185 3960);
FORCEPROP 2 LASTPIN (-4175 3900) $PN CK69
J 2
(-4185 3910);
DISPLAY 0.617021 (-4185 3910);
PAINT ORANGE (-4185 3910);
FORCEPROP 2 LASTPIN (-4175 3850) $PN CK71
J 2
(-4185 3860);
DISPLAY 0.617021 (-4185 3860);
PAINT ORANGE (-4185 3860);
FORCEPROP 2 LASTPIN (-4175 3800) $PN CK73
J 2
(-4185 3810);
DISPLAY 0.617021 (-4185 3810);
PAINT ORANGE (-4185 3810);
FORCEPROP 2 LASTPIN (-4175 3750) $PN CK75
J 2
(-4185 3760);
DISPLAY 0.617021 (-4185 3760);
PAINT ORANGE (-4185 3760);
FORCEPROP 2 LASTPIN (-4175 3700) $PN CK83
J 2
(-4185 3710);
DISPLAY 0.617021 (-4185 3710);
PAINT ORANGE (-4185 3710);
FORCEPROP 2 LASTPIN (-4175 3650) $PN CK85
J 2
(-4185 3660);
DISPLAY 0.617021 (-4185 3660);
PAINT ORANGE (-4185 3660);
FORCEPROP 2 LASTPIN (-4175 3600) $PN CL8
J 2
(-4185 3610);
DISPLAY 0.617021 (-4185 3610);
PAINT ORANGE (-4185 3610);
FORCEPROP 2 LASTPIN (-4175 3550) $PN CL14
J 2
(-4185 3560);
DISPLAY 0.617021 (-4185 3560);
PAINT ORANGE (-4185 3560);
FORCEPROP 2 LASTPIN (-4175 3500) $PN CL18
J 2
(-4185 3510);
DISPLAY 0.617021 (-4185 3510);
PAINT ORANGE (-4185 3510);
FORCEPROP 2 LASTPIN (-4175 3450) $PN P45
J 2
(-4185 3460);
DISPLAY 0.617021 (-4185 3460);
PAINT ORANGE (-4185 3460);
FORCEPROP 2 LASTPIN (-4175 3400) $PN H63
J 2
(-4185 3410);
DISPLAY 0.617021 (-4185 3410);
PAINT ORANGE (-4185 3410);
FORCEPROP 2 LASTPIN (-4175 3350) $PN CL62
J 2
(-4185 3360);
DISPLAY 0.617021 (-4185 3360);
PAINT ORANGE (-4185 3360);
FORCEPROP 2 LASTPIN (-4175 3300) $PN CL64
J 2
(-4185 3310);
DISPLAY 0.617021 (-4185 3310);
PAINT ORANGE (-4185 3310);
FORCEPROP 2 LASTPIN (-4175 3250) $PN CL66
J 2
(-4185 3260);
DISPLAY 0.617021 (-4185 3260);
PAINT ORANGE (-4185 3260);
FORCEPROP 2 LASTPIN (-4175 3200) $PN CL74
J 2
(-4185 3210);
DISPLAY 0.617021 (-4185 3210);
PAINT ORANGE (-4185 3210);
FORCEPROP 2 LASTPIN (-4175 3150) $PN CL76
J 2
(-4185 3160);
DISPLAY 0.617021 (-4185 3160);
PAINT ORANGE (-4185 3160);
FORCEPROP 2 LASTPIN (-4175 3100) $PN CL78
J 2
(-4185 3110);
DISPLAY 0.617021 (-4185 3110);
PAINT ORANGE (-4185 3110);
FORCEPROP 2 LASTPIN (-4175 3050) $PN CL80
J 2
(-4185 3060);
DISPLAY 0.617021 (-4185 3060);
PAINT ORANGE (-4185 3060);
FORCEPROP 2 LASTPIN (-4175 3000) $PN CM19
J 2
(-4185 3010);
DISPLAY 0.617021 (-4185 3010);
PAINT ORANGE (-4185 3010);
FORCEPROP 2 LASTPIN (-4175 2950) $PN CM29
J 2
(-4185 2960);
DISPLAY 0.617021 (-4185 2960);
PAINT ORANGE (-4185 2960);
FORCEPROP 2 LASTPIN (-4175 2900) $PN CM5
J 2
(-4185 2910);
DISPLAY 0.617021 (-4185 2910);
PAINT ORANGE (-4185 2910);
FORCEPROP 2 LASTPIN (-4175 2850) $PN CM31
J 2
(-4185 2860);
DISPLAY 0.617021 (-4185 2860);
PAINT ORANGE (-4185 2860);
FORCEPROP 2 LASTPIN (-4175 2800) $PN CM61
J 2
(-4185 2810);
DISPLAY 0.617021 (-4185 2810);
PAINT ORANGE (-4185 2810);
FORCEPROP 2 LASTPIN (-4175 2750) $PN CM63
J 2
(-4185 2760);
DISPLAY 0.617021 (-4185 2760);
PAINT ORANGE (-4185 2760);
FORCEPROP 2 LASTPIN (-4175 2700) $PN CM67
J 2
(-4185 2710);
DISPLAY 0.617021 (-4185 2710);
PAINT ORANGE (-4185 2710);
FORCEPROP 2 LASTPIN (-4175 2650) $PN CM73
J 2
(-4185 2660);
DISPLAY 0.617021 (-4185 2660);
PAINT ORANGE (-4185 2660);
FORCEPROP 2 LASTPIN (-4175 2600) $PN CM77
J 2
(-4185 2610);
DISPLAY 0.617021 (-4185 2610);
PAINT ORANGE (-4185 2610);
FORCEPROP 2 LASTPIN (-4175 2550) $PN CM83
J 2
(-4185 2560);
DISPLAY 0.617021 (-4185 2560);
PAINT ORANGE (-4185 2560);
FORCEPROP 2 LASTPIN (-4175 2500) $PN CM85
J 2
(-4185 2510);
DISPLAY 0.617021 (-4185 2510);
PAINT ORANGE (-4185 2510);
FORCEPROP 2 LASTPIN (-4175 2450) $PN CN2
J 2
(-4185 2460);
DISPLAY 0.617021 (-4185 2460);
PAINT ORANGE (-4185 2460);
FORCEPROP 2 LASTPIN (-4175 2400) $PN CN12
J 2
(-4185 2410);
DISPLAY 0.617021 (-4185 2410);
PAINT ORANGE (-4185 2410);
FORCEPROP 2 LASTPIN (-4175 2350) $PN H61
J 2
(-4185 2360);
DISPLAY 0.617021 (-4185 2360);
PAINT ORANGE (-4185 2360);
FORCEPROP 2 LASTPIN (-4175 2300) $PN CN26
J 2
(-4185 2310);
DISPLAY 0.617021 (-4185 2310);
PAINT ORANGE (-4185 2310);
FORCEPROP 2 LASTPIN (-4175 2250) $PN CN32
J 2
(-4185 2260);
DISPLAY 0.617021 (-4185 2260);
PAINT ORANGE (-4185 2260);
FORCEPROP 2 LASTPIN (-4175 2200) $PN CN60
J 2
(-4185 2210);
DISPLAY 0.617021 (-4185 2210);
PAINT ORANGE (-4185 2210);
FORCEPROP 2 LASTPIN (-4175 2150) $PN CN62
J 2
(-4185 2160);
DISPLAY 0.617021 (-4185 2160);
PAINT ORANGE (-4185 2160);
FORCEPROP 2 LASTPIN (-4175 2100) $PN CN68
J 2
(-4185 2110);
DISPLAY 0.617021 (-4185 2110);
PAINT ORANGE (-4185 2110);
FORCEPROP 2 LASTPIN (-4175 2050) $PN CN78
J 2
(-4185 2060);
DISPLAY 0.617021 (-4185 2060);
PAINT ORANGE (-4185 2060);
FORCEPROP 2 LASTPIN (-4175 2000) $PN CP1
J 2
(-4185 2010);
DISPLAY 0.617021 (-4185 2010);
PAINT ORANGE (-4185 2010);
FORCEPROP 2 LASTPIN (-4175 1950) $PN H59
J 2
(-4185 1960);
DISPLAY 0.617021 (-4185 1960);
PAINT ORANGE (-4185 1960);
FORCEPROP 2 LASTPIN (-4175 1900) $PN CP25
J 2
(-4185 1910);
DISPLAY 0.617021 (-4185 1910);
PAINT ORANGE (-4185 1910);
FORCEPROP 2 LASTPIN (-4175 1850) $PN CP59
J 2
(-4185 1860);
DISPLAY 0.617021 (-4185 1860);
PAINT ORANGE (-4185 1860);
FORCEPROP 2 LASTPIN (-4175 1800) $PN CP69
J 2
(-4185 1810);
DISPLAY 0.617021 (-4185 1810);
PAINT ORANGE (-4185 1810);
FORCEPROP 2 LASTPIN (-4175 1750) $PN CP73
J 2
(-4185 1760);
DISPLAY 0.617021 (-4185 1760);
PAINT ORANGE (-4185 1760);
FORCEPROP 2 LASTPIN (-4175 1700) $PN CP75
J 2
(-4185 1710);
DISPLAY 0.617021 (-4185 1710);
PAINT ORANGE (-4185 1710);
FORCEPROP 2 LASTPIN (-4175 1650) $PN CP81
J 2
(-4185 1660);
DISPLAY 0.617021 (-4185 1660);
PAINT ORANGE (-4185 1660);
FORCEPROP 2 LASTPIN (-4175 1600) $PN CP83
J 2
(-4185 1610);
DISPLAY 0.617021 (-4185 1610);
PAINT ORANGE (-4185 1610);
FORCEPROP 2 LASTPIN (-4175 1550) $PN CR6
J 2
(-4185 1560);
DISPLAY 0.617021 (-4185 1560);
PAINT ORANGE (-4185 1560);
FORCEPROP 2 LASTPIN (-4175 1500) $PN CR10
J 2
(-4185 1510);
DISPLAY 0.617021 (-4185 1510);
PAINT ORANGE (-4185 1510);
FORCEPROP 2 LASTPIN (-4175 1450) $PN CR22
J 2
(-4185 1460);
DISPLAY 0.617021 (-4185 1460);
PAINT ORANGE (-4185 1460);
FORCEPROP 2 LASTPIN (-4175 1400) $PN CR24
J 2
(-4185 1410);
DISPLAY 0.617021 (-4185 1410);
PAINT ORANGE (-4185 1410);
FORCEPROP 2 LASTPIN (-4175 1350) $PN CR32
J 2
(-4185 1360);
DISPLAY 0.617021 (-4185 1360);
PAINT ORANGE (-4185 1360);
FORCEPROP 2 LASTPIN (-4175 1300) $PN CR58
J 2
(-4185 1310);
DISPLAY 0.617021 (-4185 1310);
PAINT ORANGE (-4185 1310);
FORCEPROP 2 LASTPIN (-4175 1250) $PN CR62
J 2
(-4185 1260);
DISPLAY 0.617021 (-4185 1260);
PAINT ORANGE (-4185 1260);
FORCEPROP 2 LASTPIN (-4175 1200) $PN CR64
J 2
(-4185 1210);
DISPLAY 0.617021 (-4185 1210);
PAINT ORANGE (-4185 1210);
FORCEPROP 2 LASTPIN (-4175 1150) $PN CR66
J 2
(-4185 1160);
DISPLAY 0.617021 (-4185 1160);
PAINT ORANGE (-4185 1160);
FORCEPROP 2 LASTPIN (-4175 1100) $PN CR68
J 2
(-4185 1110);
DISPLAY 0.617021 (-4185 1110);
PAINT ORANGE (-4185 1110);
FORCEPROP 2 LASTPIN (-4175 1050) $PN CR78
J 2
(-4185 1060);
DISPLAY 0.617021 (-4185 1060);
PAINT ORANGE (-4185 1060);
FORCEPROP 2 LASTPIN (-4175 1000) $PN CR86
J 2
(-4185 1010);
DISPLAY 0.617021 (-4185 1010);
PAINT ORANGE (-4185 1010);
FORCEPROP 2 LASTPIN (-4175 950) $PN H57
J 2
(-4185 960);
DISPLAY 0.617021 (-4185 960);
PAINT ORANGE (-4185 960);
FORCEPROP 2 LASTPIN (-4175 900) $PN CT13
J 2
(-4185 910);
DISPLAY 0.617021 (-4185 910);
PAINT ORANGE (-4185 910);
FORCEPROP 2 LASTPIN (-4175 850) $PN CT19
J 2
(-4185 860);
DISPLAY 0.617021 (-4185 860);
PAINT ORANGE (-4185 860);
FORCEPROP 2 LASTPIN (-4175 800) $PN CT27
J 2
(-4185 810);
DISPLAY 0.617021 (-4185 810);
PAINT ORANGE (-4185 810);
FORCEPROP 2 LASTPIN (-4175 750) $PN CT29
J 2
(-4185 760);
DISPLAY 0.617021 (-4185 760);
PAINT ORANGE (-4185 760);
FORCEPROP 2 LASTPIN (-4175 700) $PN CT33
J 2
(-4185 710);
DISPLAY 0.617021 (-4185 710);
PAINT ORANGE (-4185 710);
FORCEPROP 2 LASTPIN (-2975 4650) $PN CT35
J 0
(-2965 4660);
DISPLAY 0.617021 (-2965 4660);
PAINT ORANGE (-2965 4660);
FORCEPROP 2 LASTPIN (-2975 4600) $PN CT57
J 0
(-2965 4610);
DISPLAY 0.617021 (-2965 4610);
PAINT ORANGE (-2965 4610);
FORCEPROP 2 LASTPIN (-2975 4550) $PN CT73
J 0
(-2965 4560);
DISPLAY 0.617021 (-2965 4560);
PAINT ORANGE (-2965 4560);
FORCEPROP 2 LASTPIN (-2975 4500) $PN CT79
J 0
(-2965 4510);
DISPLAY 0.617021 (-2965 4510);
PAINT ORANGE (-2965 4510);
FORCEPROP 2 LASTPIN (-2975 4450) $PN CT83
J 0
(-2965 4460);
DISPLAY 0.617021 (-2965 4460);
PAINT ORANGE (-2965 4460);
FORCEPROP 2 LASTPIN (-2975 4400) $PN CT85
J 0
(-2965 4410);
DISPLAY 0.617021 (-2965 4410);
PAINT ORANGE (-2965 4410);
FORCEPROP 2 LASTPIN (-2975 4350) $PN CU4
J 0
(-2965 4360);
DISPLAY 0.617021 (-2965 4360);
PAINT ORANGE (-2965 4360);
FORCEPROP 2 LASTPIN (-2975 4300) $PN CU22
J 0
(-2965 4310);
DISPLAY 0.617021 (-2965 4310);
PAINT ORANGE (-2965 4310);
FORCEPROP 2 LASTPIN (-2975 4250) $PN CU28
J 0
(-2965 4260);
DISPLAY 0.617021 (-2965 4260);
PAINT ORANGE (-2965 4260);
FORCEPROP 2 LASTPIN (-2975 4200) $PN CU30
J 0
(-2965 4210);
DISPLAY 0.617021 (-2965 4210);
PAINT ORANGE (-2965 4210);
FORCEPROP 2 LASTPIN (-2975 4150) $PN CU34
J 0
(-2965 4160);
DISPLAY 0.617021 (-2965 4160);
PAINT ORANGE (-2965 4160);
FORCEPROP 2 LASTPIN (-2975 4100) $PN CU36
J 0
(-2965 4110);
DISPLAY 0.617021 (-2965 4110);
PAINT ORANGE (-2965 4110);
FORCEPROP 2 LASTPIN (-2975 4050) $PN CU56
J 0
(-2965 4060);
DISPLAY 0.617021 (-2965 4060);
PAINT ORANGE (-2965 4060);
FORCEPROP 2 LASTPIN (-2975 4000) $PN CU62
J 0
(-2965 4010);
DISPLAY 0.617021 (-2965 4010);
PAINT ORANGE (-2965 4010);
FORCEPROP 2 LASTPIN (-2975 3950) $PN CU68
J 0
(-2965 3960);
DISPLAY 0.617021 (-2965 3960);
PAINT ORANGE (-2965 3960);
FORCEPROP 2 LASTPIN (-2975 3850) $PN CU78
J 0
(-2965 3860);
DISPLAY 0.617021 (-2965 3860);
PAINT ORANGE (-2965 3860);
FORCEPROP 2 LASTPIN (-2975 3800) $PN CU80
J 0
(-2965 3810);
DISPLAY 0.617021 (-2965 3810);
PAINT ORANGE (-2965 3810);
FORCEPROP 2 LASTPIN (-2975 3750) $PN CU82
J 0
(-2965 3760);
DISPLAY 0.617021 (-2965 3760);
PAINT ORANGE (-2965 3760);
FORCEPROP 2 LASTPIN (-2975 3650) $PN CV1
J 0
(-2965 3660);
DISPLAY 0.617021 (-2965 3660);
PAINT ORANGE (-2965 3660);
FORCEPROP 2 LASTPIN (-2975 3600) $PN H55
J 0
(-2965 3610);
DISPLAY 0.617021 (-2965 3610);
PAINT ORANGE (-2965 3610);
FORCEPROP 2 LASTPIN (-2975 3550) $PN CV17
J 0
(-2965 3560);
DISPLAY 0.617021 (-2965 3560);
PAINT ORANGE (-2965 3560);
FORCEPROP 2 LASTPIN (-2975 3500) $PN CV25
J 0
(-2965 3510);
DISPLAY 0.617021 (-2965 3510);
PAINT ORANGE (-2965 3510);
FORCEPROP 2 LASTPIN (-2975 3450) $PN CV27
J 0
(-2965 3460);
DISPLAY 0.617021 (-2965 3460);
PAINT ORANGE (-2965 3460);
FORCEPROP 2 LASTPIN (-2975 3400) $PN CV31
J 0
(-2965 3410);
DISPLAY 0.617021 (-2965 3410);
PAINT ORANGE (-2965 3410);
FORCEPROP 2 LASTPIN (-2975 3350) $PN CV33
J 0
(-2965 3360);
DISPLAY 0.617021 (-2965 3360);
PAINT ORANGE (-2965 3360);
FORCEPROP 2 LASTPIN (-2975 3300) $PN CV37
J 0
(-2965 3310);
DISPLAY 0.617021 (-2965 3310);
PAINT ORANGE (-2965 3310);
FORCEPROP 2 LASTPIN (-2975 3250) $PN CV39
J 0
(-2965 3260);
DISPLAY 0.617021 (-2965 3260);
PAINT ORANGE (-2965 3260);
FORCEPROP 2 LASTPIN (-2975 3200) $PN CV41
J 0
(-2965 3210);
DISPLAY 0.617021 (-2965 3210);
PAINT ORANGE (-2965 3210);
FORCEPROP 2 LASTPIN (-2975 3150) $PN CV53
J 0
(-2965 3160);
DISPLAY 0.617021 (-2965 3160);
PAINT ORANGE (-2965 3160);
FORCEPROP 2 LASTPIN (-2975 3100) $PN CV55
J 0
(-2965 3110);
DISPLAY 0.617021 (-2965 3110);
PAINT ORANGE (-2965 3110);
FORCEPROP 2 LASTPIN (-2975 3050) $PN CV63
J 0
(-2965 3060);
DISPLAY 0.617021 (-2965 3060);
PAINT ORANGE (-2965 3060);
FORCEPROP 2 LASTPIN (-2975 3000) $PN CV67
J 0
(-2965 3010);
DISPLAY 0.617021 (-2965 3010);
PAINT ORANGE (-2965 3010);
FORCEPROP 2 LASTPIN (-2975 2950) $PN CV73
J 0
(-2965 2960);
DISPLAY 0.617021 (-2965 2960);
PAINT ORANGE (-2965 2960);
FORCEPROP 2 LASTPIN (-2975 2900) $PN CV79
J 0
(-2965 2910);
DISPLAY 0.617021 (-2965 2910);
PAINT ORANGE (-2965 2910);
FORCEPROP 2 LASTPIN (-2975 2850) $PN CV81
J 0
(-2965 2860);
DISPLAY 0.617021 (-2965 2860);
PAINT ORANGE (-2965 2860);
FORCEPROP 2 LASTPIN (-2975 2800) $PN CV83
J 0
(-2965 2810);
DISPLAY 0.617021 (-2965 2810);
PAINT ORANGE (-2965 2810);
FORCEPROP 2 LASTPIN (-2975 2750) $PN CW12
J 0
(-2965 2760);
DISPLAY 0.617021 (-2965 2760);
PAINT ORANGE (-2965 2760);
FORCEPROP 2 LASTPIN (-2975 2700) $PN CW26
J 0
(-2965 2710);
DISPLAY 0.617021 (-2965 2710);
PAINT ORANGE (-2965 2710);
FORCEPROP 2 LASTPIN (-2975 2650) $PN CW32
J 0
(-2965 2660);
DISPLAY 0.617021 (-2965 2660);
PAINT ORANGE (-2965 2660);
FORCEPROP 2 LASTPIN (-2975 2600) $PN CW38
J 0
(-2965 2610);
DISPLAY 0.617021 (-2965 2610);
PAINT ORANGE (-2965 2610);
FORCEPROP 2 LASTPIN (-2975 2550) $PN CW40
J 0
(-2965 2560);
DISPLAY 0.617021 (-2965 2560);
PAINT ORANGE (-2965 2560);
FORCEPROP 2 LASTPIN (-2975 2500) $PN CW42
J 0
(-2965 2510);
DISPLAY 0.617021 (-2965 2510);
PAINT ORANGE (-2965 2510);
FORCEPROP 2 LASTPIN (-2975 2450) $PN CW52
J 0
(-2965 2460);
DISPLAY 0.617021 (-2965 2460);
PAINT ORANGE (-2965 2460);
FORCEPROP 2 LASTPIN (-2975 2400) $PN CW54
J 0
(-2965 2410);
DISPLAY 0.617021 (-2965 2410);
PAINT ORANGE (-2965 2410);
FORCEPROP 2 LASTPIN (-2975 2350) $PN CW64
J 0
(-2965 2360);
DISPLAY 0.617021 (-2965 2360);
PAINT ORANGE (-2965 2360);
FORCEPROP 2 LASTPIN (-2975 2300) $PN CW66
J 0
(-2965 2310);
DISPLAY 0.617021 (-2965 2310);
PAINT ORANGE (-2965 2310);
FORCEPROP 2 LASTPIN (-2975 2250) $PN CW68
J 0
(-2965 2260);
DISPLAY 0.617021 (-2965 2260);
PAINT ORANGE (-2965 2260);
FORCEPROP 2 LASTPIN (-2975 2200) $PN CW74
J 0
(-2965 2210);
DISPLAY 0.617021 (-2965 2210);
PAINT ORANGE (-2965 2210);
FORCEPROP 2 LASTPIN (-2975 2150) $PN CW78
J 0
(-2965 2160);
DISPLAY 0.617021 (-2965 2160);
PAINT ORANGE (-2965 2160);
FORCEPROP 2 LASTPIN (-2975 2100) $PN CW82
J 0
(-2965 2110);
DISPLAY 0.617021 (-2965 2110);
PAINT ORANGE (-2965 2110);
FORCEPROP 2 LASTPIN (-2975 2050) $PN CY1
J 0
(-2965 2060);
DISPLAY 0.617021 (-2965 2060);
PAINT ORANGE (-2965 2060);
FORCEPROP 2 LASTPIN (-2975 2000) $PN CY9
J 0
(-2965 2010);
DISPLAY 0.617021 (-2965 2010);
PAINT ORANGE (-2965 2010);
FORCEPROP 2 LASTPIN (-2975 1950) $PN CY13
J 0
(-2965 1960);
DISPLAY 0.617021 (-2965 1960);
PAINT ORANGE (-2965 1960);
FORCEPROP 2 LASTPIN (-2975 1900) $PN CY15
J 0
(-2965 1910);
DISPLAY 0.617021 (-2965 1910);
PAINT ORANGE (-2965 1910);
FORCEPROP 2 LASTPIN (-2975 1850) $PN CY21
J 0
(-2965 1860);
DISPLAY 0.617021 (-2965 1860);
PAINT ORANGE (-2965 1860);
FORCEPROP 2 LASTPIN (-2975 1800) $PN CY41
J 0
(-2965 1810);
DISPLAY 0.617021 (-2965 1810);
PAINT ORANGE (-2965 1810);
FORCEPROP 2 LASTPIN (-2975 1750) $PN CY45
J 0
(-2965 1760);
DISPLAY 0.617021 (-2965 1760);
PAINT ORANGE (-2965 1760);
FORCEPROP 2 LASTPIN (-2975 1700) $PN CY51
J 0
(-2965 1710);
DISPLAY 0.617021 (-2965 1710);
PAINT ORANGE (-2965 1710);
FORCEPROP 2 LASTPIN (-2975 1650) $PN CY59
J 0
(-2965 1660);
DISPLAY 0.617021 (-2965 1660);
PAINT ORANGE (-2965 1660);
FORCEPROP 2 LASTPIN (-2975 1600) $PN CY61
J 0
(-2965 1610);
DISPLAY 0.617021 (-2965 1610);
PAINT ORANGE (-2965 1610);
FORCEPROP 2 LASTPIN (-2975 1550) $PN CY65
J 0
(-2965 1560);
DISPLAY 0.617021 (-2965 1560);
PAINT ORANGE (-2965 1560);
FORCEPROP 2 LASTPIN (-2975 1500) $PN CY69
J 0
(-2965 1510);
DISPLAY 0.617021 (-2965 1510);
PAINT ORANGE (-2965 1510);
FORCEPROP 2 LASTPIN (-2975 1450) $PN CY75
J 0
(-2965 1460);
DISPLAY 0.617021 (-2965 1460);
PAINT ORANGE (-2965 1460);
FORCEPROP 2 LASTPIN (-2975 1400) $PN CY77
J 0
(-2965 1410);
DISPLAY 0.617021 (-2965 1410);
PAINT ORANGE (-2965 1410);
FORCEPROP 2 LASTPIN (-2975 1350) $PN CY83
J 0
(-2965 1360);
DISPLAY 0.617021 (-2965 1360);
PAINT ORANGE (-2965 1360);
FORCEPROP 2 LASTPIN (-2975 1300) $PN CY85
J 0
(-2965 1310);
DISPLAY 0.617021 (-2965 1310);
PAINT ORANGE (-2965 1310);
FORCEPROP 2 LASTPIN (-2975 1250) $PN DA6
J 0
(-2965 1260);
DISPLAY 0.617021 (-2965 1260);
PAINT ORANGE (-2965 1260);
FORCEPROP 2 LASTPIN (-2975 1200) $PN H53
J 0
(-2965 1210);
DISPLAY 0.617021 (-2965 1210);
PAINT ORANGE (-2965 1210);
FORCEPROP 2 LASTPIN (-2975 1150) $PN DA18
J 0
(-2965 1160);
DISPLAY 0.617021 (-2965 1160);
PAINT ORANGE (-2965 1160);
FORCEPROP 2 LASTPIN (-2975 1100) $PN DA26
J 0
(-2965 1110);
DISPLAY 0.617021 (-2965 1110);
PAINT ORANGE (-2965 1110);
FORCEPROP 2 LASTPIN (-2975 1050) $PN DA28
J 0
(-2965 1060);
DISPLAY 0.617021 (-2965 1060);
PAINT ORANGE (-2965 1060);
FORCEPROP 2 LASTPIN (-2975 1000) $PN DA30
J 0
(-2965 1010);
DISPLAY 0.617021 (-2965 1010);
PAINT ORANGE (-2965 1010);
FORCEPROP 2 LASTPIN (-2975 950) $PN DA32
J 0
(-2965 960);
DISPLAY 0.617021 (-2965 960);
PAINT ORANGE (-2965 960);
FORCEPROP 2 LASTPIN (-2975 900) $PN DA34
J 0
(-2965 910);
DISPLAY 0.617021 (-2965 910);
PAINT ORANGE (-2965 910);
FORCEPROP 2 LASTPIN (-2975 850) $PN DA36
J 0
(-2965 860);
DISPLAY 0.617021 (-2965 860);
PAINT ORANGE (-2965 860);
FORCEPROP 2 LASTPIN (-2975 800) $PN DA38
J 0
(-2965 810);
DISPLAY 0.617021 (-2965 810);
PAINT ORANGE (-2965 810);
FORCEPROP 2 LASTPIN (-2975 750) $PN DA44
J 0
(-2965 760);
DISPLAY 0.617021 (-2965 760);
PAINT ORANGE (-2965 760);
FORCEPROP 2 LASTPIN (-2975 700) $PN DA46
J 0
(-2965 710);
DISPLAY 0.617021 (-2965 710);
PAINT ORANGE (-2965 710);
FORCEPROP 2 LASTPIN (-2975 3900) $PN CU76
J 0
(-2965 3910);
DISPLAY 0.617021 (-2965 3910);
PAINT ORANGE (-2965 3910);
FORCEPROP 2 LASTPIN (-2975 3700) $PN CU86
J 0
(-2965 3710);
DISPLAY 0.617021 (-2965 3710);
PAINT ORANGE (-2965 3710);
FORCEPROP 1 LAST PACK_TYPE BGA1
J 0
(-4125 4950);
PAINT SKYBLUE (-4125 4950);
DISPLAY INVISIBLE (-4125 4950);
FORCEPROP 2 LAST CDS_LIB chpset_lib
J 0
(-3575 2650);
PAINT ORANGE (-3575 2650);
DISPLAY INVISIBLE (-3575 2650);
FORCEPROP 2 LAST SEC_TYPE BGA1
J 0
(-4125 4950);
DISPLAY 1.021277 (-4125 4950);
PAINT ORANGE (-4125 4950);
DISPLAY INVISIBLE (-4125 4950);
FORCEPROP 2 LAST SEC 28
J 0
(-4125 4950);
DISPLAY 0.680851 (-4125 4950);
PAINT MONO (-4125 4950);
DISPLAY INVISIBLE (-4125 4950);
FORCEPROP 2 LAST CDS_LOCATION U5D1
J 0
(-4125 4900);
DISPLAY 0.617021 (-4125 4900);
PAINT AQUA (-4125 4900);
DISPLAY INVISIBLE (-4125 4900);
FORCEPROP 1 LAST PATH I284
J 0
(-3575 4850);
PAINT GREEN (-3575 4850);
DISPLAY INVISIBLE (-3575 4850);
FORCEPROP 0 LAST ROOM CPU0
J 0
(-4125 5000);
DISPLAY 1.021277 (-4125 5000);
PAINT ORANGE (-4125 5000);
DISPLAY INVISIBLE (-4125 5000);
FORCEADD SKX_EXT_B..29
(-1850 2600);
FORCEPROP 2 LASTPIN (-1250 4450) $PN DG82
J 0
(-1240 4460);
DISPLAY 0.617021 (-1240 4460);
PAINT ORANGE (-1240 4460);
FORCEPROP 1 LAST LOCATION U5D1
J 0
(-2400 4850);
DISPLAY 0.617021 (-2400 4850);
PAINT AQUA (-2400 4850);
FORCEPROP 1 LAST PART_NUMBER TBD
J 0
(-2400 450);
DISPLAY 0.617021 (-2400 450);
PAINT BLUE (-2400 450);
FORCEPROP 1 LAST MATERIAL IC
J 0
(-2400 4800);
DISPLAY 0.617021 (-2400 4800);
PAINT SKYBLUE (-2400 4800);
FORCEPROP 2 LASTPIN (-2450 4600) $PN DA48
J 2
(-2460 4610);
DISPLAY 0.617021 (-2460 4610);
PAINT ORANGE (-2460 4610);
FORCEPROP 2 LASTPIN (-2450 4550) $PN DA50
J 2
(-2460 4560);
DISPLAY 0.617021 (-2460 4560);
PAINT ORANGE (-2460 4560);
FORCEPROP 2 LASTPIN (-2450 4500) $PN DA64
J 2
(-2460 4510);
DISPLAY 0.617021 (-2460 4510);
PAINT ORANGE (-2460 4510);
FORCEPROP 2 LASTPIN (-2450 4450) $PN DA70
J 2
(-2460 4460);
DISPLAY 0.617021 (-2460 4460);
PAINT ORANGE (-2460 4460);
FORCEPROP 2 LASTPIN (-2450 4400) $PN DA74
J 2
(-2460 4410);
DISPLAY 0.617021 (-2460 4410);
PAINT ORANGE (-2460 4410);
FORCEPROP 2 LASTPIN (-2450 4350) $PN DA76
J 2
(-2460 4360);
DISPLAY 0.617021 (-2460 4360);
PAINT ORANGE (-2460 4360);
FORCEPROP 2 LASTPIN (-2450 4250) $PN DA80
J 2
(-2460 4260);
DISPLAY 0.617021 (-2460 4260);
PAINT ORANGE (-2460 4260);
FORCEPROP 2 LASTPIN (-2450 4200) $PN DB3
J 2
(-2460 4210);
DISPLAY 0.617021 (-2460 4210);
PAINT ORANGE (-2460 4210);
FORCEPROP 2 LASTPIN (-2450 4150) $PN DB13
J 2
(-2460 4160);
DISPLAY 0.617021 (-2460 4160);
PAINT ORANGE (-2460 4160);
FORCEPROP 2 LASTPIN (-2450 4100) $PN DB17
J 2
(-2460 4110);
DISPLAY 0.617021 (-2460 4110);
PAINT ORANGE (-2460 4110);
FORCEPROP 2 LASTPIN (-2450 4050) $PN DB23
J 2
(-2460 4060);
DISPLAY 0.617021 (-2460 4060);
PAINT ORANGE (-2460 4060);
FORCEPROP 2 LASTPIN (-2450 4000) $PN DB25
J 2
(-2460 4010);
DISPLAY 0.617021 (-2460 4010);
PAINT ORANGE (-2460 4010);
FORCEPROP 2 LASTPIN (-2450 3950) $PN DB39
J 2
(-2460 3960);
DISPLAY 0.617021 (-2460 3960);
PAINT ORANGE (-2460 3960);
FORCEPROP 2 LASTPIN (-2450 3900) $PN DB41
J 2
(-2460 3910);
DISPLAY 0.617021 (-2460 3910);
PAINT ORANGE (-2460 3910);
FORCEPROP 2 LASTPIN (-2450 3850) $PN DB47
J 2
(-2460 3860);
DISPLAY 0.617021 (-2460 3860);
PAINT ORANGE (-2460 3860);
FORCEPROP 2 LASTPIN (-2450 3800) $PN DB49
J 2
(-2460 3810);
DISPLAY 0.617021 (-2460 3810);
PAINT ORANGE (-2460 3810);
FORCEPROP 2 LASTPIN (-2450 3750) $PN DB73
J 2
(-2460 3760);
DISPLAY 0.617021 (-2460 3760);
PAINT ORANGE (-2460 3760);
FORCEPROP 2 LASTPIN (-2450 3700) $PN DB77
J 2
(-2460 3710);
DISPLAY 0.617021 (-2460 3710);
PAINT ORANGE (-2460 3710);
FORCEPROP 2 LASTPIN (-2450 3650) $PN DB83
J 2
(-2460 3660);
DISPLAY 0.617021 (-2460 3660);
PAINT ORANGE (-2460 3660);
FORCEPROP 2 LASTPIN (-2450 3550) $PN DC14
J 2
(-2460 3560);
DISPLAY 0.617021 (-2460 3560);
PAINT ORANGE (-2460 3560);
FORCEPROP 2 LASTPIN (-2450 3500) $PN DC24
J 2
(-2460 3510);
DISPLAY 0.617021 (-2460 3510);
PAINT ORANGE (-2460 3510);
FORCEPROP 2 LASTPIN (-2450 3450) $PN DC26
J 2
(-2460 3460);
DISPLAY 0.617021 (-2460 3460);
PAINT ORANGE (-2460 3460);
FORCEPROP 2 LASTPIN (-2450 3400) $PN DC32
J 2
(-2460 3410);
DISPLAY 0.617021 (-2460 3410);
PAINT ORANGE (-2460 3410);
FORCEPROP 2 LASTPIN (-2450 3350) $PN DC38
J 2
(-2460 3360);
DISPLAY 0.617021 (-2460 3360);
PAINT ORANGE (-2460 3360);
FORCEPROP 2 LASTPIN (-2450 3300) $PN DC42
J 2
(-2460 3310);
DISPLAY 0.617021 (-2460 3310);
PAINT ORANGE (-2460 3310);
FORCEPROP 2 LASTPIN (-2450 3250) $PN DC64
J 2
(-2460 3260);
DISPLAY 0.617021 (-2460 3260);
PAINT ORANGE (-2460 3260);
FORCEPROP 2 LASTPIN (-2450 3200) $PN DC66
J 2
(-2460 3210);
DISPLAY 0.617021 (-2460 3210);
PAINT ORANGE (-2460 3210);
FORCEPROP 2 LASTPIN (-2450 3150) $PN DC68
J 2
(-2460 3160);
DISPLAY 0.617021 (-2460 3160);
PAINT ORANGE (-2460 3160);
FORCEPROP 2 LASTPIN (-2450 3100) $PN DC70
J 2
(-2460 3110);
DISPLAY 0.617021 (-2460 3110);
PAINT ORANGE (-2460 3110);
FORCEPROP 2 LASTPIN (-2450 3050) $PN DC78
J 2
(-2460 3060);
DISPLAY 0.617021 (-2460 3060);
PAINT ORANGE (-2460 3060);
FORCEPROP 2 LASTPIN (-2450 3000) $PN DC84
J 2
(-2460 3010);
DISPLAY 0.617021 (-2460 3010);
PAINT ORANGE (-2460 3010);
FORCEPROP 2 LASTPIN (-2450 2950) $PN DC86
J 2
(-2460 2960);
DISPLAY 0.617021 (-2460 2960);
PAINT ORANGE (-2460 2960);
FORCEPROP 2 LASTPIN (-2450 2900) $PN DD11
J 2
(-2460 2910);
DISPLAY 0.617021 (-2460 2910);
PAINT ORANGE (-2460 2910);
FORCEPROP 2 LASTPIN (-2450 2850) $PN DD23
J 2
(-2460 2860);
DISPLAY 0.617021 (-2460 2860);
PAINT ORANGE (-2460 2860);
FORCEPROP 2 LASTPIN (-2450 2800) $PN DD27
J 2
(-2460 2810);
DISPLAY 0.617021 (-2460 2810);
PAINT ORANGE (-2460 2810);
FORCEPROP 2 LASTPIN (-2450 2750) $PN DD31
J 2
(-2460 2760);
DISPLAY 0.617021 (-2460 2760);
PAINT ORANGE (-2460 2760);
FORCEPROP 2 LASTPIN (-2450 2700) $PN DD33
J 2
(-2460 2710);
DISPLAY 0.617021 (-2460 2710);
PAINT ORANGE (-2460 2710);
FORCEPROP 2 LASTPIN (-2450 2650) $PN DD37
J 2
(-2460 2660);
DISPLAY 0.617021 (-2460 2660);
PAINT ORANGE (-2460 2660);
FORCEPROP 2 LASTPIN (-2450 2600) $PN DD71
J 2
(-2460 2610);
DISPLAY 0.617021 (-2460 2610);
PAINT ORANGE (-2460 2610);
FORCEPROP 2 LASTPIN (-2450 2550) $PN DD73
J 2
(-2460 2560);
DISPLAY 0.617021 (-2460 2560);
PAINT ORANGE (-2460 2560);
FORCEPROP 2 LASTPIN (-2450 2500) $PN DD75
J 2
(-2460 2510);
DISPLAY 0.617021 (-2460 2510);
PAINT ORANGE (-2460 2510);
FORCEPROP 2 LASTPIN (-2450 2450) $PN DD81
J 2
(-2460 2460);
DISPLAY 0.617021 (-2460 2460);
PAINT ORANGE (-2460 2460);
FORCEPROP 2 LASTPIN (-2450 2400) $PN DD83
J 2
(-2460 2410);
DISPLAY 0.617021 (-2460 2410);
PAINT ORANGE (-2460 2410);
FORCEPROP 2 LASTPIN (-2450 2350) $PN DE6
J 2
(-2460 2360);
DISPLAY 0.617021 (-2460 2360);
PAINT ORANGE (-2460 2360);
FORCEPROP 2 LASTPIN (-2450 2300) $PN DE8
J 2
(-2460 2310);
DISPLAY 0.617021 (-2460 2310);
PAINT ORANGE (-2460 2310);
FORCEPROP 2 LASTPIN (-2450 2250) $PN DE18
J 2
(-2460 2260);
DISPLAY 0.617021 (-2460 2260);
PAINT ORANGE (-2460 2260);
FORCEPROP 2 LASTPIN (-2450 2200) $PN DE20
J 2
(-2460 2210);
DISPLAY 0.617021 (-2460 2210);
PAINT ORANGE (-2460 2210);
FORCEPROP 2 LASTPIN (-2450 2150) $PN DE24
J 2
(-2460 2160);
DISPLAY 0.617021 (-2460 2160);
PAINT ORANGE (-2460 2160);
FORCEPROP 2 LASTPIN (-2450 2100) $PN DE28
J 2
(-2460 2110);
DISPLAY 0.617021 (-2460 2110);
PAINT ORANGE (-2460 2110);
FORCEPROP 2 LASTPIN (-2450 2050) $PN DE30
J 2
(-2460 2060);
DISPLAY 0.617021 (-2460 2060);
PAINT ORANGE (-2460 2060);
FORCEPROP 2 LASTPIN (-2450 2000) $PN DE34
J 2
(-2460 2010);
DISPLAY 0.617021 (-2460 2010);
PAINT ORANGE (-2460 2010);
FORCEPROP 2 LASTPIN (-2450 1950) $PN DE36
J 2
(-2460 1960);
DISPLAY 0.617021 (-2460 1960);
PAINT ORANGE (-2460 1960);
FORCEPROP 2 LASTPIN (-2450 1900) $PN DE64
J 2
(-2460 1910);
DISPLAY 0.617021 (-2460 1910);
PAINT ORANGE (-2460 1910);
FORCEPROP 2 LASTPIN (-2450 1850) $PN DE70
J 2
(-2460 1860);
DISPLAY 0.617021 (-2460 1860);
PAINT ORANGE (-2460 1860);
FORCEPROP 2 LASTPIN (-2450 1800) $PN DE72
J 2
(-2460 1810);
DISPLAY 0.617021 (-2460 1810);
PAINT ORANGE (-2460 1810);
FORCEPROP 2 LASTPIN (-2450 1750) $PN DE78
J 2
(-2460 1760);
DISPLAY 0.617021 (-2460 1760);
PAINT ORANGE (-2460 1760);
FORCEPROP 2 LASTPIN (-2450 1700) $PN DF5
J 2
(-2460 1710);
DISPLAY 0.617021 (-2460 1710);
PAINT ORANGE (-2460 1710);
FORCEPROP 2 LASTPIN (-2450 1650) $PN DF7
J 2
(-2460 1660);
DISPLAY 0.617021 (-2460 1660);
PAINT ORANGE (-2460 1660);
FORCEPROP 2 LASTPIN (-2450 1600) $PN H51
J 2
(-2460 1610);
DISPLAY 0.617021 (-2460 1610);
PAINT ORANGE (-2460 1610);
FORCEPROP 2 LASTPIN (-2450 1550) $PN DF19
J 2
(-2460 1560);
DISPLAY 0.617021 (-2460 1560);
PAINT ORANGE (-2460 1560);
FORCEPROP 2 LASTPIN (-2450 1500) $PN DF29
J 2
(-2460 1510);
DISPLAY 0.617021 (-2460 1510);
PAINT ORANGE (-2460 1510);
FORCEPROP 2 LASTPIN (-2450 1450) $PN DF35
J 2
(-2460 1460);
DISPLAY 0.617021 (-2460 1460);
PAINT ORANGE (-2460 1460);
FORCEPROP 2 LASTPIN (-2450 1400) $PN DF37
J 2
(-2460 1410);
DISPLAY 0.617021 (-2460 1410);
PAINT ORANGE (-2460 1410);
FORCEPROP 2 LASTPIN (-2450 1350) $PN DF39
J 2
(-2460 1360);
DISPLAY 0.617021 (-2460 1360);
PAINT ORANGE (-2460 1360);
FORCEPROP 2 LASTPIN (-2450 1300) $PN DF41
J 2
(-2460 1310);
DISPLAY 0.617021 (-2460 1310);
PAINT ORANGE (-2460 1310);
FORCEPROP 2 LASTPIN (-2450 1250) $PN DF65
J 2
(-2460 1260);
DISPLAY 0.617021 (-2460 1260);
PAINT ORANGE (-2460 1260);
FORCEPROP 2 LASTPIN (-2450 1150) $PN DF73
J 2
(-2460 1160);
DISPLAY 0.617021 (-2460 1160);
PAINT ORANGE (-2460 1160);
FORCEPROP 2 LASTPIN (-2450 1100) $PN DF79
J 2
(-2460 1110);
DISPLAY 0.617021 (-2460 1110);
PAINT ORANGE (-2460 1110);
FORCEPROP 2 LASTPIN (-2450 1050) $PN DF83
J 2
(-2460 1060);
DISPLAY 0.617021 (-2460 1060);
PAINT ORANGE (-2460 1060);
FORCEPROP 2 LASTPIN (-2450 1000) $PN DF85
J 2
(-2460 1010);
DISPLAY 0.617021 (-2460 1010);
PAINT ORANGE (-2460 1010);
FORCEPROP 2 LASTPIN (-2450 950) $PN DG2
J 2
(-2460 960);
DISPLAY 0.617021 (-2460 960);
PAINT ORANGE (-2460 960);
FORCEPROP 2 LASTPIN (-2450 900) $PN H49
J 2
(-2460 910);
DISPLAY 0.617021 (-2460 910);
PAINT ORANGE (-2460 910);
FORCEPROP 2 LASTPIN (-2450 850) $PN DG14
J 2
(-2460 860);
DISPLAY 0.617021 (-2460 860);
PAINT ORANGE (-2460 860);
FORCEPROP 2 LASTPIN (-2450 800) $PN DG16
J 2
(-2460 810);
DISPLAY 0.617021 (-2460 810);
PAINT ORANGE (-2460 810);
FORCEPROP 2 LASTPIN (-2450 750) $PN DG24
J 2
(-2460 760);
DISPLAY 0.617021 (-2460 760);
PAINT ORANGE (-2460 760);
FORCEPROP 2 LASTPIN (-2450 700) $PN DG66
J 2
(-2460 710);
DISPLAY 0.617021 (-2460 710);
PAINT ORANGE (-2460 710);
FORCEPROP 2 LASTPIN (-2450 650) $PN DG68
J 2
(-2460 660);
DISPLAY 0.617021 (-2460 660);
PAINT ORANGE (-2460 660);
FORCEPROP 2 LASTPIN (-1250 4600) $PN DG76
J 0
(-1240 4610);
DISPLAY 0.617021 (-1240 4610);
PAINT ORANGE (-1240 4610);
FORCEPROP 2 LASTPIN (-1250 4550) $PN DG78
J 0
(-1240 4560);
DISPLAY 0.617021 (-1240 4560);
PAINT ORANGE (-1240 4560);
FORCEPROP 2 LASTPIN (-1250 4500) $PN DG80
J 0
(-1240 4510);
DISPLAY 0.617021 (-1240 4510);
PAINT ORANGE (-1240 4510);
FORCEPROP 2 LASTPIN (-1250 4400) $PN DH13
J 0
(-1240 4410);
DISPLAY 0.617021 (-1240 4410);
PAINT ORANGE (-1240 4410);
FORCEPROP 2 LASTPIN (-1250 4350) $PN DH15
J 0
(-1240 4360);
DISPLAY 0.617021 (-1240 4360);
PAINT ORANGE (-1240 4360);
FORCEPROP 2 LASTPIN (-1250 4300) $PN DH23
J 0
(-1240 4310);
DISPLAY 0.617021 (-1240 4310);
PAINT ORANGE (-1240 4310);
FORCEPROP 2 LASTPIN (-1250 4250) $PN DH25
J 0
(-1240 4260);
DISPLAY 0.617021 (-1240 4260);
PAINT ORANGE (-1240 4260);
FORCEPROP 2 LASTPIN (-1250 4200) $PN DH27
J 0
(-1240 4210);
DISPLAY 0.617021 (-1240 4210);
PAINT ORANGE (-1240 4210);
FORCEPROP 2 LASTPIN (-1250 4150) $PN DH29
J 0
(-1240 4160);
DISPLAY 0.617021 (-1240 4160);
PAINT ORANGE (-1240 4160);
FORCEPROP 2 LASTPIN (-1250 4100) $PN DH31
J 0
(-1240 4110);
DISPLAY 0.617021 (-1240 4110);
PAINT ORANGE (-1240 4110);
FORCEPROP 2 LASTPIN (-1250 4050) $PN DH33
J 0
(-1240 4060);
DISPLAY 0.617021 (-1240 4060);
PAINT ORANGE (-1240 4060);
FORCEPROP 2 LASTPIN (-1250 4000) $PN DH35
J 0
(-1240 4010);
DISPLAY 0.617021 (-1240 4010);
PAINT ORANGE (-1240 4010);
FORCEPROP 2 LASTPIN (-1250 3950) $PN DH37
J 0
(-1240 3960);
DISPLAY 0.617021 (-1240 3960);
PAINT ORANGE (-1240 3960);
FORCEPROP 2 LASTPIN (-1250 3900) $PN DH41
J 0
(-1240 3910);
DISPLAY 0.617021 (-1240 3910);
PAINT ORANGE (-1240 3910);
FORCEPROP 2 LASTPIN (-1250 3850) $PN DH67
J 0
(-1240 3860);
DISPLAY 0.617021 (-1240 3860);
PAINT ORANGE (-1240 3860);
FORCEPROP 2 LASTPIN (-1250 3800) $PN DH71
J 0
(-1240 3810);
DISPLAY 0.617021 (-1240 3810);
PAINT ORANGE (-1240 3810);
FORCEPROP 2 LASTPIN (-1250 3750) $PN DH73
J 0
(-1240 3760);
DISPLAY 0.617021 (-1240 3760);
PAINT ORANGE (-1240 3760);
FORCEPROP 2 LASTPIN (-1250 3700) $PN DH79
J 0
(-1240 3710);
DISPLAY 0.617021 (-1240 3710);
PAINT ORANGE (-1240 3710);
FORCEPROP 2 LASTPIN (-1250 3650) $PN DH81
J 0
(-1240 3660);
DISPLAY 0.617021 (-1240 3660);
PAINT ORANGE (-1240 3660);
FORCEPROP 2 LASTPIN (-1250 3550) $PN DJ2
J 0
(-1240 3560);
DISPLAY 0.617021 (-1240 3560);
PAINT ORANGE (-1240 3560);
FORCEPROP 2 LASTPIN (-1250 3500) $PN DJ10
J 0
(-1240 3510);
DISPLAY 0.617021 (-1240 3510);
PAINT ORANGE (-1240 3510);
FORCEPROP 2 LASTPIN (-1250 3450) $PN H47
J 0
(-1240 3460);
DISPLAY 0.617021 (-1240 3460);
PAINT ORANGE (-1240 3460);
FORCEPROP 2 LASTPIN (-1250 3400) $PN DJ22
J 0
(-1240 3410);
DISPLAY 0.617021 (-1240 3410);
PAINT ORANGE (-1240 3410);
FORCEPROP 2 LASTPIN (-1250 3350) $PN DJ38
J 0
(-1240 3360);
DISPLAY 0.617021 (-1240 3360);
PAINT ORANGE (-1240 3360);
FORCEPROP 2 LASTPIN (-1250 3300) $PN DJ42
J 0
(-1240 3310);
DISPLAY 0.617021 (-1240 3310);
PAINT ORANGE (-1240 3310);
FORCEPROP 2 LASTPIN (-1250 3250) $PN DJ68
J 0
(-1240 3260);
DISPLAY 0.617021 (-1240 3260);
PAINT ORANGE (-1240 3260);
FORCEPROP 2 LASTPIN (-1250 3200) $PN DJ74
J 0
(-1240 3210);
DISPLAY 0.617021 (-1240 3210);
PAINT ORANGE (-1240 3210);
FORCEPROP 2 LASTPIN (-1250 3150) $PN DJ78
J 0
(-1240 3160);
DISPLAY 0.617021 (-1240 3160);
PAINT ORANGE (-1240 3160);
FORCEPROP 2 LASTPIN (-1250 3100) $PN DJ82
J 0
(-1240 3110);
DISPLAY 0.617021 (-1240 3110);
PAINT ORANGE (-1240 3110);
FORCEPROP 2 LASTPIN (-1250 3050) $PN DJ84
J 0
(-1240 3060);
DISPLAY 0.617021 (-1240 3060);
PAINT ORANGE (-1240 3060);
FORCEPROP 2 LASTPIN (-1250 3000) $PN DK7
J 0
(-1240 3010);
DISPLAY 0.617021 (-1240 3010);
PAINT ORANGE (-1240 3010);
FORCEPROP 2 LASTPIN (-1250 2950) $PN DK23
J 0
(-1240 2960);
DISPLAY 0.617021 (-1240 2960);
PAINT ORANGE (-1240 2960);
FORCEPROP 2 LASTPIN (-1250 2900) $PN DK29
J 0
(-1240 2910);
DISPLAY 0.617021 (-1240 2910);
PAINT ORANGE (-1240 2910);
FORCEPROP 2 LASTPIN (-1250 2850) $PN DK35
J 0
(-1240 2860);
DISPLAY 0.617021 (-1240 2860);
PAINT ORANGE (-1240 2860);
FORCEPROP 2 LASTPIN (-1250 2800) $PN DK39
J 0
(-1240 2810);
DISPLAY 0.617021 (-1240 2810);
PAINT ORANGE (-1240 2810);
FORCEPROP 2 LASTPIN (-1250 2750) $PN DK41
J 0
(-1240 2760);
DISPLAY 0.617021 (-1240 2760);
PAINT ORANGE (-1240 2760);
FORCEPROP 2 LASTPIN (-1250 2700) $PN DK73
J 0
(-1240 2710);
DISPLAY 0.617021 (-1240 2710);
PAINT ORANGE (-1240 2710);
FORCEPROP 2 LASTPIN (-1250 2650) $PN DK75
J 0
(-1240 2660);
DISPLAY 0.617021 (-1240 2660);
PAINT ORANGE (-1240 2660);
FORCEPROP 2 LASTPIN (-1250 2550) $PN DK83
J 0
(-1240 2560);
DISPLAY 0.617021 (-1240 2560);
PAINT ORANGE (-1240 2560);
FORCEPROP 2 LASTPIN (-1250 2500) $PN DK85
J 0
(-1240 2510);
DISPLAY 0.617021 (-1240 2510);
PAINT ORANGE (-1240 2510);
FORCEPROP 2 LASTPIN (-1250 2450) $PN DL16
J 0
(-1240 2460);
DISPLAY 0.617021 (-1240 2460);
PAINT ORANGE (-1240 2460);
FORCEPROP 2 LASTPIN (-1250 2400) $PN DL18
J 0
(-1240 2410);
DISPLAY 0.617021 (-1240 2410);
PAINT ORANGE (-1240 2410);
FORCEPROP 2 LASTPIN (-1250 2350) $PN DL4
J 0
(-1240 2360);
DISPLAY 0.617021 (-1240 2360);
PAINT ORANGE (-1240 2360);
FORCEPROP 2 LASTPIN (-1250 2300) $PN DL22
J 0
(-1240 2310);
DISPLAY 0.617021 (-1240 2310);
PAINT ORANGE (-1240 2310);
FORCEPROP 2 LASTPIN (-1250 2250) $PN DL24
J 0
(-1240 2260);
DISPLAY 0.617021 (-1240 2260);
PAINT ORANGE (-1240 2260);
FORCEPROP 2 LASTPIN (-1250 2200) $PN DL28
J 0
(-1240 2210);
DISPLAY 0.617021 (-1240 2210);
PAINT ORANGE (-1240 2210);
FORCEPROP 2 LASTPIN (-1250 2150) $PN DL30
J 0
(-1240 2160);
DISPLAY 0.617021 (-1240 2160);
PAINT ORANGE (-1240 2160);
FORCEPROP 2 LASTPIN (-1250 2100) $PN DL34
J 0
(-1240 2110);
DISPLAY 0.617021 (-1240 2110);
PAINT ORANGE (-1240 2110);
FORCEPROP 2 LASTPIN (-1250 2050) $PN DL36
J 0
(-1240 2060);
DISPLAY 0.617021 (-1240 2060);
PAINT ORANGE (-1240 2060);
FORCEPROP 2 LASTPIN (-1250 2000) $PN DL40
J 0
(-1240 2010);
DISPLAY 0.617021 (-1240 2010);
PAINT ORANGE (-1240 2010);
FORCEPROP 2 LASTPIN (-1250 1950) $PN DL68
J 0
(-1240 1960);
DISPLAY 0.617021 (-1240 1960);
PAINT ORANGE (-1240 1960);
FORCEPROP 2 LASTPIN (-1250 1900) $PN DL70
J 0
(-1240 1910);
DISPLAY 0.617021 (-1240 1910);
PAINT ORANGE (-1240 1910);
FORCEPROP 2 LASTPIN (-1250 1850) $PN DL74
J 0
(-1240 1860);
DISPLAY 0.617021 (-1240 1860);
PAINT ORANGE (-1240 1860);
FORCEPROP 2 LASTPIN (-1250 1800) $PN DL76
J 0
(-1240 1810);
DISPLAY 0.617021 (-1240 1810);
PAINT ORANGE (-1240 1810);
FORCEPROP 2 LASTPIN (-1250 1750) $PN DL78
J 0
(-1240 1760);
DISPLAY 0.617021 (-1240 1760);
PAINT ORANGE (-1240 1760);
FORCEPROP 2 LASTPIN (-1250 1700) $PN DL80
J 0
(-1240 1710);
DISPLAY 0.617021 (-1240 1710);
PAINT ORANGE (-1240 1710);
FORCEPROP 2 LASTPIN (-1250 1650) $PN DM15
J 0
(-1240 1660);
DISPLAY 0.617021 (-1240 1660);
PAINT ORANGE (-1240 1660);
FORCEPROP 2 LASTPIN (-1250 1600) $PN H45
J 0
(-1240 1610);
DISPLAY 0.617021 (-1240 1610);
PAINT ORANGE (-1240 1610);
FORCEPROP 2 LASTPIN (-1250 1550) $PN DM25
J 0
(-1240 1560);
DISPLAY 0.617021 (-1240 1560);
PAINT ORANGE (-1240 1560);
FORCEPROP 2 LASTPIN (-1250 1500) $PN DM27
J 0
(-1240 1510);
DISPLAY 0.617021 (-1240 1510);
PAINT ORANGE (-1240 1510);
FORCEPROP 2 LASTPIN (-1250 1450) $PN DM31
J 0
(-1240 1460);
DISPLAY 0.617021 (-1240 1460);
PAINT ORANGE (-1240 1460);
FORCEPROP 2 LASTPIN (-1250 1400) $PN DM33
J 0
(-1240 1410);
DISPLAY 0.617021 (-1240 1410);
PAINT ORANGE (-1240 1410);
FORCEPROP 2 LASTPIN (-1250 1350) $PN DM37
J 0
(-1240 1360);
DISPLAY 0.617021 (-1240 1360);
PAINT ORANGE (-1240 1360);
FORCEPROP 2 LASTPIN (-1250 1300) $PN DM39
J 0
(-1240 1310);
DISPLAY 0.617021 (-1240 1310);
PAINT ORANGE (-1240 1310);
FORCEPROP 2 LASTPIN (-1250 1250) $PN DM65
J 0
(-1240 1260);
DISPLAY 0.617021 (-1240 1260);
PAINT ORANGE (-1240 1260);
FORCEPROP 2 LASTPIN (-1250 1200) $PN DM73
J 0
(-1240 1210);
DISPLAY 0.617021 (-1240 1210);
PAINT ORANGE (-1240 1210);
FORCEPROP 2 LASTPIN (-1250 1150) $PN DM77
J 0
(-1240 1160);
DISPLAY 0.617021 (-1240 1160);
PAINT ORANGE (-1240 1160);
FORCEPROP 2 LASTPIN (-1250 1100) $PN DM83
J 0
(-1240 1110);
DISPLAY 0.617021 (-1240 1110);
PAINT ORANGE (-1240 1110);
FORCEPROP 2 LASTPIN (-1250 1050) $PN DN2
J 0
(-1240 1060);
DISPLAY 0.617021 (-1240 1060);
PAINT ORANGE (-1240 1060);
FORCEPROP 2 LASTPIN (-1250 1000) $PN BH17
J 0
(-1240 1010);
DISPLAY 0.617021 (-1240 1010);
PAINT ORANGE (-1240 1010);
FORCEPROP 2 LASTPIN (-1250 950) $PN DN12
J 0
(-1240 960);
DISPLAY 0.617021 (-1240 960);
PAINT ORANGE (-1240 960);
FORCEPROP 2 LASTPIN (-1250 900) $PN DN22
J 0
(-1240 910);
DISPLAY 0.617021 (-1240 910);
PAINT ORANGE (-1240 910);
FORCEPROP 2 LASTPIN (-1250 850) $PN DN26
J 0
(-1240 860);
DISPLAY 0.617021 (-1240 860);
PAINT ORANGE (-1240 860);
FORCEPROP 2 LASTPIN (-1250 800) $PN DN32
J 0
(-1240 810);
DISPLAY 0.617021 (-1240 810);
PAINT ORANGE (-1240 810);
FORCEPROP 2 LASTPIN (-1250 750) $PN DN38
J 0
(-1240 760);
DISPLAY 0.617021 (-1240 760);
PAINT ORANGE (-1240 760);
FORCEPROP 2 LASTPIN (-1250 700) $PN DN68
J 0
(-1240 710);
DISPLAY 0.617021 (-1240 710);
PAINT ORANGE (-1240 710);
FORCEPROP 2 LASTPIN (-1250 650) $PN DN72
J 0
(-1240 660);
DISPLAY 0.617021 (-1240 660);
PAINT ORANGE (-1240 660);
FORCEPROP 2 LASTPIN (-2450 1200) $PN DF69
J 2
(-2460 1210);
DISPLAY 0.617021 (-2460 1210);
PAINT ORANGE (-2460 1210);
FORCEPROP 2 LASTPIN (-1250 3600) $PN DH83
J 0
(-1240 3610);
DISPLAY 0.617021 (-1240 3610);
PAINT ORANGE (-1240 3610);
FORCEPROP 2 LASTPIN (-1250 2600) $PN DK77
J 0
(-1240 2610);
DISPLAY 0.617021 (-1240 2610);
PAINT ORANGE (-1240 2610);
FORCEPROP 2 LASTPIN (-2450 4300) $PN DA78
J 2
(-2460 4310);
DISPLAY 0.617021 (-2460 4310);
PAINT ORANGE (-2460 4310);
FORCEPROP 2 LASTPIN (-2450 3600) $PN DB85
J 2
(-2460 3610);
DISPLAY 0.617021 (-2460 3610);
PAINT ORANGE (-2460 3610);
FORCEPROP 1 LAST PACK_TYPE BGA1
J 0
(-2400 4900);
PAINT SKYBLUE (-2400 4900);
DISPLAY INVISIBLE (-2400 4900);
FORCEPROP 2 LAST CDS_LIB chpset_lib
J 0
(-1850 2600);
PAINT ORANGE (-1850 2600);
DISPLAY INVISIBLE (-1850 2600);
FORCEPROP 2 LAST SEC_TYPE BGA1
J 0
(-2400 4900);
DISPLAY 1.021277 (-2400 4900);
PAINT ORANGE (-2400 4900);
DISPLAY INVISIBLE (-2400 4900);
FORCEPROP 2 LAST SEC 29
J 0
(-2400 4900);
DISPLAY 0.680851 (-2400 4900);
PAINT MONO (-2400 4900);
DISPLAY INVISIBLE (-2400 4900);
FORCEPROP 2 LAST CDS_LOCATION U5D1
J 0
(-2400 4850);
DISPLAY 0.617021 (-2400 4850);
PAINT AQUA (-2400 4850);
DISPLAY INVISIBLE (-2400 4850);
FORCEPROP 1 LAST PATH I285
J 0
(-1850 4800);
PAINT GREEN (-1850 4800);
DISPLAY INVISIBLE (-1850 4800);
FORCEPROP 0 LAST ROOM CPU0
J 0
(-2400 4950);
DISPLAY 1.021277 (-2400 4950);
PAINT ORANGE (-2400 4950);
DISPLAY INVISIBLE (-2400 4950);
FORCEADD SKX_EXT_B..30
(-175 2650);
FORCEPROP 1 LAST LOCATION U5D1
J 0
(-725 4900);
DISPLAY 0.617021 (-725 4900);
PAINT AQUA (-725 4900);
FORCEPROP 1 LAST PART_NUMBER TBD
J 0
(-725 500);
DISPLAY 0.617021 (-725 500);
PAINT BLUE (-725 500);
FORCEPROP 1 LAST MATERIAL IC
J 0
(-725 4850);
DISPLAY 0.617021 (-725 4850);
PAINT SKYBLUE (-725 4850);
FORCEPROP 2 LASTPIN (-775 4650) $PN DN78
J 2
(-785 4660);
DISPLAY 0.617021 (-785 4660);
PAINT ORANGE (-785 4660);
FORCEPROP 2 LASTPIN (-775 4600) $PN DP67
J 2
(-785 4610);
DISPLAY 0.617021 (-785 4610);
PAINT ORANGE (-785 4610);
FORCEPROP 2 LASTPIN (-775 4500) $PN DP71
J 2
(-785 4510);
DISPLAY 0.617021 (-785 4510);
PAINT ORANGE (-785 4510);
FORCEPROP 2 LASTPIN (-775 4450) $PN DP81
J 2
(-785 4460);
DISPLAY 0.617021 (-785 4460);
PAINT ORANGE (-785 4460);
FORCEPROP 2 LASTPIN (-775 4400) $PN DP83
J 2
(-785 4410);
DISPLAY 0.617021 (-785 4410);
PAINT ORANGE (-785 4410);
FORCEPROP 2 LASTPIN (-775 4350) $PN BR26
J 2
(-785 4360);
DISPLAY 0.617021 (-785 4360);
PAINT ORANGE (-785 4360);
FORCEPROP 2 LASTPIN (-775 4300) $PN DR6
J 2
(-785 4310);
DISPLAY 0.617021 (-785 4310);
PAINT ORANGE (-785 4310);
FORCEPROP 2 LASTPIN (-775 4250) $PN CA20
J 2
(-785 4260);
DISPLAY 0.617021 (-785 4260);
PAINT ORANGE (-785 4260);
FORCEPROP 2 LASTPIN (-775 4200) $PN CL22
J 2
(-785 4210);
DISPLAY 0.617021 (-785 4210);
PAINT ORANGE (-785 4210);
FORCEPROP 2 LASTPIN (-775 4150) $PN DR20
J 2
(-785 4160);
DISPLAY 0.617021 (-785 4160);
PAINT ORANGE (-785 4160);
FORCEPROP 2 LASTPIN (-775 4100) $PN DR22
J 2
(-785 4110);
DISPLAY 0.617021 (-785 4110);
PAINT ORANGE (-785 4110);
FORCEPROP 2 LASTPIN (-775 4050) $PN DR24
J 2
(-785 4060);
DISPLAY 0.617021 (-785 4060);
PAINT ORANGE (-785 4060);
FORCEPROP 2 LASTPIN (-775 4000) $PN DR26
J 2
(-785 4010);
DISPLAY 0.617021 (-785 4010);
PAINT ORANGE (-785 4010);
FORCEPROP 2 LASTPIN (-775 3950) $PN DR28
J 2
(-785 3960);
DISPLAY 0.617021 (-785 3960);
PAINT ORANGE (-785 3960);
FORCEPROP 2 LASTPIN (-775 3900) $PN DR30
J 2
(-785 3910);
DISPLAY 0.617021 (-785 3910);
PAINT ORANGE (-785 3910);
FORCEPROP 2 LASTPIN (-775 3850) $PN DR32
J 2
(-785 3860);
DISPLAY 0.617021 (-785 3860);
PAINT ORANGE (-785 3860);
FORCEPROP 2 LASTPIN (-775 3800) $PN DR34
J 2
(-785 3810);
DISPLAY 0.617021 (-785 3810);
PAINT ORANGE (-785 3810);
FORCEPROP 2 LASTPIN (-775 3750) $PN DR36
J 2
(-785 3760);
DISPLAY 0.617021 (-785 3760);
PAINT ORANGE (-785 3760);
FORCEPROP 2 LASTPIN (-775 3650) $PN DR40
J 2
(-785 3660);
DISPLAY 0.617021 (-785 3660);
PAINT ORANGE (-785 3660);
FORCEPROP 2 LASTPIN (-775 3600) $PN DR42
J 2
(-785 3610);
DISPLAY 0.617021 (-785 3610);
PAINT ORANGE (-785 3610);
FORCEPROP 2 LASTPIN (-775 3550) $PN DR66
J 2
(-785 3560);
DISPLAY 0.617021 (-785 3560);
PAINT ORANGE (-785 3560);
FORCEPROP 2 LASTPIN (-775 3500) $PN DR68
J 2
(-785 3510);
DISPLAY 0.617021 (-785 3510);
PAINT ORANGE (-785 3510);
FORCEPROP 2 LASTPIN (-775 3450) $PN DR70
J 2
(-785 3460);
DISPLAY 0.617021 (-785 3460);
PAINT ORANGE (-785 3460);
FORCEPROP 2 LASTPIN (-775 3400) $PN DR72
J 2
(-785 3410);
DISPLAY 0.617021 (-785 3410);
PAINT ORANGE (-785 3410);
FORCEPROP 2 LASTPIN (-775 3350) $PN DR74
J 2
(-785 3360);
DISPLAY 0.617021 (-785 3360);
PAINT ORANGE (-785 3360);
FORCEPROP 2 LASTPIN (-775 3300) $PN DR76
J 2
(-785 3310);
DISPLAY 0.617021 (-785 3310);
PAINT ORANGE (-785 3310);
FORCEPROP 2 LASTPIN (-775 3250) $PN DR78
J 2
(-785 3260);
DISPLAY 0.617021 (-785 3260);
PAINT ORANGE (-785 3260);
FORCEPROP 2 LASTPIN (-775 3200) $PN DT3
J 2
(-785 3210);
DISPLAY 0.617021 (-785 3210);
PAINT ORANGE (-785 3210);
FORCEPROP 2 LASTPIN (-775 3150) $PN DT17
J 2
(-785 3160);
DISPLAY 0.617021 (-785 3160);
PAINT ORANGE (-785 3160);
FORCEPROP 2 LASTPIN (-775 3100) $PN DH21
J 2
(-785 3110);
DISPLAY 0.617021 (-785 3110);
PAINT ORANGE (-785 3110);
FORCEPROP 2 LASTPIN (-775 3050) $PN DT65
J 2
(-785 3060);
DISPLAY 0.617021 (-785 3060);
PAINT ORANGE (-785 3060);
FORCEPROP 2 LASTPIN (-775 3000) $PN DT69
J 2
(-785 3010);
DISPLAY 0.617021 (-785 3010);
PAINT ORANGE (-785 3010);
FORCEPROP 2 LASTPIN (-775 2950) $PN DT79
J 2
(-785 2960);
DISPLAY 0.617021 (-785 2960);
PAINT ORANGE (-785 2960);
FORCEPROP 2 LASTPIN (-775 2900) $PN DT83
J 2
(-785 2910);
DISPLAY 0.617021 (-785 2910);
PAINT ORANGE (-785 2910);
FORCEPROP 2 LASTPIN (-775 2850) $PN DT85
J 2
(-785 2860);
DISPLAY 0.617021 (-785 2860);
PAINT ORANGE (-785 2860);
FORCEPROP 2 LASTPIN (-775 2800) $PN DU10
J 2
(-785 2810);
DISPLAY 0.617021 (-785 2810);
PAINT ORANGE (-785 2810);
FORCEPROP 2 LASTPIN (-775 2750) $PN DU14
J 2
(-785 2760);
DISPLAY 0.617021 (-785 2760);
PAINT ORANGE (-785 2760);
FORCEPROP 2 LASTPIN (-775 2700) $PN CN14
J 2
(-785 2710);
DISPLAY 0.617021 (-785 2710);
PAINT ORANGE (-785 2710);
FORCEPROP 2 LASTPIN (-775 2650) $PN DU22
J 2
(-785 2660);
DISPLAY 0.617021 (-785 2660);
PAINT ORANGE (-785 2660);
FORCEPROP 2 LASTPIN (-775 2600) $PN DU26
J 2
(-785 2610);
DISPLAY 0.617021 (-785 2610);
PAINT ORANGE (-785 2610);
FORCEPROP 2 LASTPIN (-775 2550) $PN DU32
J 2
(-785 2560);
DISPLAY 0.617021 (-785 2560);
PAINT ORANGE (-785 2560);
FORCEPROP 2 LASTPIN (-775 2500) $PN DU38
J 2
(-785 2510);
DISPLAY 0.617021 (-785 2510);
PAINT ORANGE (-785 2510);
FORCEPROP 2 LASTPIN (-775 2450) $PN DU70
J 2
(-785 2460);
DISPLAY 0.617021 (-785 2460);
PAINT ORANGE (-785 2460);
FORCEPROP 2 LASTPIN (-775 2400) $PN DU72
J 2
(-785 2410);
DISPLAY 0.617021 (-785 2410);
PAINT ORANGE (-785 2410);
FORCEPROP 2 LASTPIN (-775 2350) $PN DU78
J 2
(-785 2360);
DISPLAY 0.617021 (-785 2360);
PAINT ORANGE (-785 2360);
FORCEPROP 2 LASTPIN (-775 2300) $PN DU80
J 2
(-785 2310);
DISPLAY 0.617021 (-785 2310);
PAINT ORANGE (-785 2310);
FORCEPROP 2 LASTPIN (-775 2250) $PN DU82
J 2
(-785 2260);
DISPLAY 0.617021 (-785 2260);
PAINT ORANGE (-785 2260);
FORCEPROP 2 LASTPIN (-775 2200) $PN DU84
J 2
(-785 2210);
DISPLAY 0.617021 (-785 2210);
PAINT ORANGE (-785 2210);
FORCEPROP 2 LASTPIN (-775 2150) $PN DV21
J 2
(-785 2160);
DISPLAY 0.617021 (-785 2160);
PAINT ORANGE (-785 2160);
FORCEPROP 2 LASTPIN (-775 2100) $PN DV25
J 2
(-785 2110);
DISPLAY 0.617021 (-785 2110);
PAINT ORANGE (-785 2110);
FORCEPROP 2 LASTPIN (-775 2050) $PN DV27
J 2
(-785 2060);
DISPLAY 0.617021 (-785 2060);
PAINT ORANGE (-785 2060);
FORCEPROP 2 LASTPIN (-775 2000) $PN DV31
J 2
(-785 2010);
DISPLAY 0.617021 (-785 2010);
PAINT ORANGE (-785 2010);
FORCEPROP 2 LASTPIN (-775 1950) $PN DV33
J 2
(-785 1960);
DISPLAY 0.617021 (-785 1960);
PAINT ORANGE (-785 1960);
FORCEPROP 2 LASTPIN (-775 1900) $PN DV37
J 2
(-785 1910);
DISPLAY 0.617021 (-785 1910);
PAINT ORANGE (-785 1910);
FORCEPROP 2 LASTPIN (-775 1850) $PN DV39
J 2
(-785 1860);
DISPLAY 0.617021 (-785 1860);
PAINT ORANGE (-785 1860);
FORCEPROP 2 LASTPIN (-775 1800) $PN DV73
J 2
(-785 1810);
DISPLAY 0.617021 (-785 1810);
PAINT ORANGE (-785 1810);
FORCEPROP 2 LASTPIN (-775 1750) $PN DV77
J 2
(-785 1760);
DISPLAY 0.617021 (-785 1760);
PAINT ORANGE (-785 1760);
FORCEPROP 2 LASTPIN (-775 1700) $PN DV81
J 2
(-785 1710);
DISPLAY 0.617021 (-785 1710);
PAINT ORANGE (-785 1710);
FORCEPROP 2 LASTPIN (-775 1650) $PN DW12
J 2
(-785 1660);
DISPLAY 0.617021 (-785 1660);
PAINT ORANGE (-785 1660);
FORCEPROP 2 LASTPIN (-775 1600) $PN DW20
J 2
(-785 1610);
DISPLAY 0.617021 (-785 1610);
PAINT ORANGE (-785 1610);
FORCEPROP 2 LASTPIN (-775 1550) $PN DW24
J 2
(-785 1560);
DISPLAY 0.617021 (-785 1560);
PAINT ORANGE (-785 1560);
FORCEPROP 2 LASTPIN (-775 1500) $PN DW28
J 2
(-785 1510);
DISPLAY 0.617021 (-785 1510);
PAINT ORANGE (-785 1510);
FORCEPROP 2 LASTPIN (-775 1450) $PN DW30
J 2
(-785 1460);
DISPLAY 0.617021 (-785 1460);
PAINT ORANGE (-785 1460);
FORCEPROP 2 LASTPIN (-775 1400) $PN DW34
J 2
(-785 1410);
DISPLAY 0.617021 (-785 1410);
PAINT ORANGE (-785 1410);
FORCEPROP 2 LASTPIN (-775 1350) $PN DW36
J 2
(-785 1360);
DISPLAY 0.617021 (-785 1360);
PAINT ORANGE (-785 1360);
FORCEPROP 2 LASTPIN (-775 1300) $PN DW40
J 2
(-785 1310);
DISPLAY 0.617021 (-785 1310);
PAINT ORANGE (-785 1310);
FORCEPROP 2 LASTPIN (-775 1250) $PN DW64
J 2
(-785 1260);
DISPLAY 0.617021 (-785 1260);
PAINT ORANGE (-785 1260);
FORCEPROP 2 LASTPIN (-775 1200) $PN DW66
J 2
(-785 1210);
DISPLAY 0.617021 (-785 1210);
PAINT ORANGE (-785 1210);
FORCEPROP 2 LASTPIN (-775 1150) $PN DW68
J 2
(-785 1160);
DISPLAY 0.617021 (-785 1160);
PAINT ORANGE (-785 1160);
FORCEPROP 2 LASTPIN (-775 1100) $PN DW70
J 2
(-785 1110);
DISPLAY 0.617021 (-785 1110);
PAINT ORANGE (-785 1110);
FORCEPROP 2 LASTPIN (-775 1050) $PN DW72
J 2
(-785 1060);
DISPLAY 0.617021 (-785 1060);
PAINT ORANGE (-785 1060);
FORCEPROP 2 LASTPIN (-775 1000) $PN DW74
J 2
(-785 1010);
DISPLAY 0.617021 (-785 1010);
PAINT ORANGE (-785 1010);
FORCEPROP 2 LASTPIN (-775 950) $PN DW76
J 2
(-785 960);
DISPLAY 0.617021 (-785 960);
PAINT ORANGE (-785 960);
FORCEPROP 2 LASTPIN (-775 900) $PN DW8
J 2
(-785 910);
DISPLAY 0.617021 (-785 910);
PAINT ORANGE (-785 910);
FORCEPROP 2 LASTPIN (-775 850) $PN DW82
J 2
(-785 860);
DISPLAY 0.617021 (-785 860);
PAINT ORANGE (-785 860);
FORCEPROP 2 LASTPIN (-775 800) $PN DW84
J 2
(-785 810);
DISPLAY 0.617021 (-785 810);
PAINT ORANGE (-785 810);
FORCEPROP 2 LASTPIN (-775 750) $PN DY5
J 2
(-785 760);
DISPLAY 0.617021 (-785 760);
PAINT ORANGE (-785 760);
FORCEPROP 2 LASTPIN (-775 700) $PN DY19
J 2
(-785 710);
DISPLAY 0.617021 (-785 710);
PAINT ORANGE (-785 710);
FORCEPROP 2 LASTPIN (425 4650) $PN DY23
J 0
(435 4660);
DISPLAY 0.617021 (435 4660);
PAINT ORANGE (435 4660);
FORCEPROP 2 LASTPIN (425 4600) $PN DY29
J 0
(435 4610);
DISPLAY 0.617021 (435 4610);
PAINT ORANGE (435 4610);
FORCEPROP 2 LASTPIN (425 4550) $PN DY35
J 0
(435 4560);
DISPLAY 0.617021 (435 4560);
PAINT ORANGE (435 4560);
FORCEPROP 2 LASTPIN (425 4500) $PN DY41
J 0
(435 4510);
DISPLAY 0.617021 (435 4510);
PAINT ORANGE (435 4510);
FORCEPROP 2 LASTPIN (425 4450) $PN DY71
J 0
(435 4460);
DISPLAY 0.617021 (435 4460);
PAINT ORANGE (435 4460);
FORCEPROP 2 LASTPIN (425 4400) $PN DY75
J 0
(435 4410);
DISPLAY 0.617021 (435 4410);
PAINT ORANGE (435 4410);
FORCEPROP 2 LASTPIN (425 4350) $PN EA6
J 0
(435 4360);
DISPLAY 0.617021 (435 4360);
PAINT ORANGE (435 4360);
FORCEPROP 2 LASTPIN (425 4300) $PN J16
J 0
(435 4310);
DISPLAY 0.617021 (435 4310);
PAINT ORANGE (435 4310);
FORCEPROP 2 LASTPIN (425 4250) $PN EA16
J 0
(435 4260);
DISPLAY 0.617021 (435 4260);
PAINT ORANGE (435 4260);
FORCEPROP 2 LASTPIN (425 4200) $PN EA20
J 0
(435 4210);
DISPLAY 0.617021 (435 4210);
PAINT ORANGE (435 4210);
FORCEPROP 2 LASTPIN (425 4150) $PN EA22
J 0
(435 4160);
DISPLAY 0.617021 (435 4160);
PAINT ORANGE (435 4160);
FORCEPROP 2 LASTPIN (425 4100) $PN EA42
J 0
(435 4110);
DISPLAY 0.617021 (435 4110);
PAINT ORANGE (435 4110);
FORCEPROP 2 LASTPIN (425 4050) $PN EA64
J 0
(435 4060);
DISPLAY 0.617021 (435 4060);
PAINT ORANGE (435 4060);
FORCEPROP 2 LASTPIN (425 4000) $PN EA70
J 0
(435 4010);
DISPLAY 0.617021 (435 4010);
PAINT ORANGE (435 4010);
FORCEPROP 2 LASTPIN (425 3950) $PN EA76
J 0
(435 3960);
DISPLAY 0.617021 (435 3960);
PAINT ORANGE (435 3960);
FORCEPROP 2 LASTPIN (425 3900) $PN EA78
J 0
(435 3910);
DISPLAY 0.617021 (435 3910);
PAINT ORANGE (435 3910);
FORCEPROP 2 LASTPIN (425 3850) $PN EA80
J 0
(435 3860);
DISPLAY 0.617021 (435 3860);
PAINT ORANGE (435 3860);
FORCEPROP 2 LASTPIN (425 3800) $PN EA82
J 0
(435 3810);
DISPLAY 0.617021 (435 3810);
PAINT ORANGE (435 3810);
FORCEPROP 2 LASTPIN (425 3750) $PN EB13
J 0
(435 3760);
DISPLAY 0.617021 (435 3760);
PAINT ORANGE (435 3760);
FORCEPROP 2 LASTPIN (425 3700) $PN BR18
J 0
(435 3710);
DISPLAY 0.617021 (435 3710);
PAINT ORANGE (435 3710);
FORCEPROP 2 LASTPIN (425 3650) $PN EB23
J 0
(435 3660);
DISPLAY 0.617021 (435 3660);
PAINT ORANGE (435 3660);
FORCEPROP 2 LASTPIN (425 3600) $PN EB25
J 0
(435 3610);
DISPLAY 0.617021 (435 3610);
PAINT ORANGE (435 3610);
FORCEPROP 2 LASTPIN (425 3550) $PN EB27
J 0
(435 3560);
DISPLAY 0.617021 (435 3560);
PAINT ORANGE (435 3560);
FORCEPROP 2 LASTPIN (425 3500) $PN EB29
J 0
(435 3510);
DISPLAY 0.617021 (435 3510);
PAINT ORANGE (435 3510);
FORCEPROP 2 LASTPIN (425 3450) $PN EB31
J 0
(435 3460);
DISPLAY 0.617021 (435 3460);
PAINT ORANGE (435 3460);
FORCEPROP 2 LASTPIN (425 3400) $PN EB33
J 0
(435 3410);
DISPLAY 0.617021 (435 3410);
PAINT ORANGE (435 3410);
FORCEPROP 2 LASTPIN (425 3350) $PN EB35
J 0
(435 3360);
DISPLAY 0.617021 (435 3360);
PAINT ORANGE (435 3360);
FORCEPROP 2 LASTPIN (425 3300) $PN EB37
J 0
(435 3310);
DISPLAY 0.617021 (435 3310);
PAINT ORANGE (435 3310);
FORCEPROP 2 LASTPIN (425 3250) $PN EB39
J 0
(435 3260);
DISPLAY 0.617021 (435 3260);
PAINT ORANGE (435 3260);
FORCEPROP 2 LASTPIN (425 3200) $PN EB41
J 0
(435 3210);
DISPLAY 0.617021 (435 3210);
PAINT ORANGE (435 3210);
FORCEPROP 2 LASTPIN (425 3150) $PN EB65
J 0
(435 3160);
DISPLAY 0.617021 (435 3160);
PAINT ORANGE (435 3160);
FORCEPROP 2 LASTPIN (425 3100) $PN EB69
J 0
(435 3110);
DISPLAY 0.617021 (435 3110);
PAINT ORANGE (435 3110);
FORCEPROP 2 LASTPIN (425 3050) $PN EC10
J 0
(435 3060);
DISPLAY 0.617021 (435 3060);
PAINT ORANGE (435 3060);
FORCEPROP 2 LASTPIN (425 3000) $PN EC70
J 0
(435 3010);
DISPLAY 0.617021 (435 3010);
PAINT ORANGE (435 3010);
FORCEPROP 2 LASTPIN (425 2950) $PN EC72
J 0
(435 2960);
DISPLAY 0.617021 (435 2960);
PAINT ORANGE (435 2960);
FORCEPROP 2 LASTPIN (425 2900) $PN EC74
J 0
(435 2910);
DISPLAY 0.617021 (435 2910);
PAINT ORANGE (435 2910);
FORCEPROP 2 LASTPIN (425 2850) $PN EC76
J 0
(435 2860);
DISPLAY 0.617021 (435 2860);
PAINT ORANGE (435 2860);
FORCEPROP 2 LASTPIN (425 2800) $PN ED11
J 0
(435 2810);
DISPLAY 0.617021 (435 2810);
PAINT ORANGE (435 2810);
FORCEPROP 2 LASTPIN (425 2750) $PN ED15
J 0
(435 2760);
DISPLAY 0.617021 (435 2760);
PAINT ORANGE (435 2760);
FORCEPROP 2 LASTPIN (425 2700) $PN ED23
J 0
(435 2710);
DISPLAY 0.617021 (435 2710);
PAINT ORANGE (435 2710);
FORCEPROP 2 LASTPIN (425 2650) $PN ED29
J 0
(435 2660);
DISPLAY 0.617021 (435 2660);
PAINT ORANGE (435 2660);
FORCEPROP 2 LASTPIN (425 2600) $PN ED35
J 0
(435 2610);
DISPLAY 0.617021 (435 2610);
PAINT ORANGE (435 2610);
FORCEPROP 2 LASTPIN (425 2500) $PN EE24
J 0
(435 2510);
DISPLAY 0.617021 (435 2510);
PAINT ORANGE (435 2510);
FORCEPROP 2 LASTPIN (425 2450) $PN EE28
J 0
(435 2460);
DISPLAY 0.617021 (435 2460);
PAINT ORANGE (435 2460);
FORCEPROP 2 LASTPIN (425 2400) $PN EE30
J 0
(435 2410);
DISPLAY 0.617021 (435 2410);
PAINT ORANGE (435 2410);
FORCEPROP 2 LASTPIN (425 2350) $PN EE34
J 0
(435 2360);
DISPLAY 0.617021 (435 2360);
PAINT ORANGE (435 2360);
FORCEPROP 2 LASTPIN (425 2300) $PN EE36
J 0
(435 2310);
DISPLAY 0.617021 (435 2310);
PAINT ORANGE (435 2310);
FORCEPROP 2 LASTPIN (425 2250) $PN EE70
J 0
(435 2260);
DISPLAY 0.617021 (435 2260);
PAINT ORANGE (435 2260);
FORCEPROP 2 LASTPIN (425 2200) $PN EE76
J 0
(435 2210);
DISPLAY 0.617021 (435 2210);
PAINT ORANGE (435 2210);
FORCEPROP 2 LASTPIN (425 2150) $PN EE78
J 0
(435 2160);
DISPLAY 0.617021 (435 2160);
PAINT ORANGE (435 2160);
FORCEPROP 2 LASTPIN (425 2100) $PN EF71
J 0
(435 2110);
DISPLAY 0.617021 (435 2110);
PAINT ORANGE (435 2110);
FORCEPROP 2 LASTPIN (425 2050) $PN EF75
J 0
(435 2060);
DISPLAY 0.617021 (435 2060);
PAINT ORANGE (435 2060);
FORCEPROP 2 LASTPIN (425 2000) $PN EF79
J 0
(435 2010);
DISPLAY 0.617021 (435 2010);
PAINT ORANGE (435 2010);
FORCEPROP 2 LASTPIN (-775 3700) $PN DR38
J 2
(-785 3710);
DISPLAY 0.617021 (-785 3710);
PAINT ORANGE (-785 3710);
FORCEPROP 2 LASTPIN (425 2550) $PN ED77
J 0
(435 2560);
DISPLAY 0.617021 (435 2560);
PAINT ORANGE (435 2560);
FORCEPROP 2 LASTPIN (-775 4550) $PN DP69
J 2
(-785 4560);
DISPLAY 0.617021 (-785 4560);
PAINT ORANGE (-785 4560);
FORCEPROP 1 LAST PACK_TYPE BGA1
J 0
(-725 4950);
PAINT SKYBLUE (-725 4950);
DISPLAY INVISIBLE (-725 4950);
FORCEPROP 2 LAST CDS_LIB chpset_lib
J 0
(-175 2650);
PAINT ORANGE (-175 2650);
DISPLAY INVISIBLE (-175 2650);
FORCEPROP 2 LAST SEC_TYPE BGA1
J 0
(-725 4950);
DISPLAY 1.021277 (-725 4950);
PAINT ORANGE (-725 4950);
DISPLAY INVISIBLE (-725 4950);
FORCEPROP 2 LAST SEC 30
J 0
(-725 4950);
DISPLAY 0.680851 (-725 4950);
PAINT MONO (-725 4950);
DISPLAY INVISIBLE (-725 4950);
FORCEPROP 2 LAST CDS_LOCATION U5D1
J 0
(-725 4900);
DISPLAY 0.617021 (-725 4900);
PAINT AQUA (-725 4900);
DISPLAY INVISIBLE (-725 4900);
FORCEPROP 1 LAST PATH I286
J 0
(-175 4850);
PAINT GREEN (-175 4850);
DISPLAY INVISIBLE (-175 4850);
FORCEPROP 0 LAST ROOM CPU0
J 0
(-725 5000);
DISPLAY 1.021277 (-725 5000);
PAINT ORANGE (-725 5000);
DISPLAY INVISIBLE (-725 5000);
FORCEADD DESIGN_NOTE..1
(-4900 250);
FORCEPROP 0 LAST L1 CPU SYMBOLS 1-30 ARE PRELIMINARY AND SUBJECT TO CHANGE
J 0
(-5100 125);
DISPLAY 1.021277 (-5100 125);
PAINT ORANGE (-5100 125);
FORCEPROP 2 LAST CDS_LIB mstr_symbols
J 0
(-4900 250);
PAINT ORANGE (-4900 250);
DISPLAY INVISIBLE (-4900 250);
FORCEPROP 1 LAST COMMENT_BODY TRUE
J 0
(-4875 350);
DISPLAY 0.978723 (-4875 350);
PAINT ORANGE (-4875 350);
DISPLAY INVISIBLE (-4875 350);
FORCEADD INTEL_CORP_BPAGE..1
(1500 75);
FORCEPROP 1 LAST CDS_CON_LAST_MODIFIED Fri Jun 16 17:48:15 2017
J 0
(75 400);
DISPLAY 1.340426 (75 400);
PAINT GREEN (75 400);
DISPLAY INVISIBLE (75 400);
FORCEPROP 1 LAST CUSTOM_TXT_CDS <CURRENT_DESIGN_SHEET> OF <TOTAL_DESIGN_SHEETS>
J 0
(1000 100);
PAINT ORANGE (1000 100);
FORCEPROP 1 LAST CUSTOM_TXT_CDS <CON_LAST_MODIFIED>
J 0
(-2500 175);
PAINT ORANGE (-2500 175);
FORCEPROP 2 LAST CUSTOM_TXT_CDS <XR_PAGE_TITLE>
J 0
(-6390 5325);
DISPLAY 0.638298 (-6390 5325);
PAINT PINK (-6390 5325);
DISPLAY INVISIBLE (-6390 5325);
FORCEPROP 1 LAST SCH_TITLE SKYLAKE - SKT0 - 21 OF 21
J 0
(-6450 125);
DISPLAY 1.212766 (-6450 125);
PAINT GREEN (-6450 125);
FORCEPROP 2 LAST PAGE_BORDER TRUE
J 0
(-6390 5325);
DISPLAY 0.851064 (-6390 5325);
PAINT PINK (-6390 5325);
DISPLAY INVISIBLE (-6390 5325);
FORCEPROP 2 LAST CDS_LIB mstr_symbols
J 0
(1500 75);
PAINT ORANGE (1500 75);
DISPLAY INVISIBLE (1500 75);
FORCEPROP 1 LAST COMMENT_BODY TRUE
J 0
(1512 87);
DISPLAY 0.638298 (1512 87);
PAINT GREEN (1512 87);
DISPLAY INVISIBLE (1512 87);
FORCEPROP 2 LAST CDS_XR_PAGE_TITLE CR-41 : @BASEBOARD_FAB2_LIB.BASEBOARD_FAB2(SCH_1):PAGE41
J 0
(-6390 5325);
DISPLAY 0.638298 (-6390 5325);
PAINT PINK (-6390 5325);
DISPLAY INVISIBLE (-6390 5325);
WIRE 16 -1 (-4475 700)(-4475 600);
WIRE 16 -1 (-4475 750)(-4475 700);
WIRE 16 -1 (-4675 700)(-4475 700);
WIRE 16 -1 (-4475 800)(-4475 750);
WIRE 16 -1 (-4675 750)(-4475 750);
WIRE 16 -1 (-4475 850)(-4475 800);
WIRE 16 -1 (-4675 800)(-4475 800);
WIRE 16 -1 (-4475 900)(-4475 850);
WIRE 16 -1 (-4675 850)(-4475 850);
WIRE 16 -1 (-4475 950)(-4475 900);
WIRE 16 -1 (-4675 900)(-4475 900);
WIRE 16 -1 (-4475 1000)(-4475 950);
WIRE 16 -1 (-4675 950)(-4475 950);
WIRE 16 -1 (-4475 1050)(-4475 1000);
WIRE 16 -1 (-4675 1000)(-4475 1000);
WIRE 16 -1 (-4475 1100)(-4475 1050);
WIRE 16 -1 (-4675 1050)(-4475 1050);
WIRE 16 -1 (-4475 1150)(-4475 1100);
WIRE 16 -1 (-4675 1100)(-4475 1100);
WIRE 16 -1 (-4475 1200)(-4475 1150);
WIRE 16 -1 (-4675 1150)(-4475 1150);
WIRE 16 -1 (-4475 1250)(-4475 1200);
WIRE 16 -1 (-4675 1200)(-4475 1200);
WIRE 16 -1 (-4475 1300)(-4475 1250);
WIRE 16 -1 (-4675 1250)(-4475 1250);
WIRE 16 -1 (-4475 1350)(-4475 1300);
WIRE 16 -1 (-4675 1300)(-4475 1300);
WIRE 16 -1 (-4475 1400)(-4475 1350);
WIRE 16 -1 (-4675 1350)(-4475 1350);
WIRE 16 -1 (-4475 1450)(-4475 1400);
WIRE 16 -1 (-4675 1400)(-4475 1400);
WIRE 16 -1 (-4475 1500)(-4475 1450);
WIRE 16 -1 (-4675 1450)(-4475 1450);
WIRE 16 -1 (-4475 1550)(-4475 1500);
WIRE 16 -1 (-4675 1500)(-4475 1500);
WIRE 16 -1 (-4475 1600)(-4475 1550);
WIRE 16 -1 (-4675 1550)(-4475 1550);
WIRE 16 -1 (-4475 1650)(-4475 1600);
WIRE 16 -1 (-4675 1600)(-4475 1600);
WIRE 16 -1 (-4475 1700)(-4475 1650);
WIRE 16 -1 (-4675 1650)(-4475 1650);
WIRE 16 -1 (-4475 1750)(-4475 1700);
WIRE 16 -1 (-4675 1700)(-4475 1700);
WIRE 16 -1 (-4475 1800)(-4475 1750);
WIRE 16 -1 (-4675 1750)(-4475 1750);
WIRE 16 -1 (-4475 1850)(-4475 1800);
WIRE 16 -1 (-4675 1800)(-4475 1800);
WIRE 16 -1 (-4475 1900)(-4475 1850);
WIRE 16 -1 (-4675 1850)(-4475 1850);
WIRE 16 -1 (-4475 1950)(-4475 1900);
WIRE 16 -1 (-4675 1900)(-4475 1900);
WIRE 16 -1 (-4475 2000)(-4475 1950);
WIRE 16 -1 (-4675 1950)(-4475 1950);
WIRE 16 -1 (-4475 2050)(-4475 2000);
WIRE 16 -1 (-4675 2000)(-4475 2000);
WIRE 16 -1 (-4475 2100)(-4475 2050);
WIRE 16 -1 (-4675 2050)(-4475 2050);
WIRE 16 -1 (-4475 2150)(-4475 2100);
WIRE 16 -1 (-4675 2100)(-4475 2100);
WIRE 16 -1 (-4475 2200)(-4475 2150);
WIRE 16 -1 (-4675 2150)(-4475 2150);
WIRE 16 -1 (-4475 2250)(-4475 2200);
WIRE 16 -1 (-4675 2200)(-4475 2200);
WIRE 16 -1 (-4475 2300)(-4475 2250);
WIRE 16 -1 (-4675 2250)(-4475 2250);
WIRE 16 -1 (-4475 2350)(-4475 2300);
WIRE 16 -1 (-4675 2300)(-4475 2300);
WIRE 16 -1 (-4475 2400)(-4475 2350);
WIRE 16 -1 (-4675 2350)(-4475 2350);
WIRE 16 -1 (-4475 2450)(-4475 2400);
WIRE 16 -1 (-4675 2400)(-4475 2400);
WIRE 16 -1 (-4475 2500)(-4475 2450);
WIRE 16 -1 (-4675 2450)(-4475 2450);
WIRE 16 -1 (-4475 2550)(-4475 2500);
WIRE 16 -1 (-4675 2500)(-4475 2500);
WIRE 16 -1 (-4475 2600)(-4475 2550);
WIRE 16 -1 (-4675 2550)(-4475 2550);
WIRE 16 -1 (-4475 2650)(-4475 2600);
WIRE 16 -1 (-4675 2600)(-4475 2600);
WIRE 16 -1 (-4475 2700)(-4475 2650);
WIRE 16 -1 (-4675 2650)(-4475 2650);
WIRE 16 -1 (-4475 2750)(-4475 2700);
WIRE 16 -1 (-4675 2700)(-4475 2700);
WIRE 16 -1 (-4475 2800)(-4475 2750);
WIRE 16 -1 (-4675 2750)(-4475 2750);
WIRE 16 -1 (-4475 2850)(-4475 2800);
WIRE 16 -1 (-4675 2800)(-4475 2800);
WIRE 16 -1 (-4475 2900)(-4475 2850);
WIRE 16 -1 (-4675 2850)(-4475 2850);
WIRE 16 -1 (-4475 2950)(-4475 2900);
WIRE 16 -1 (-4675 2900)(-4475 2900);
WIRE 16 -1 (-4475 3000)(-4475 2950);
WIRE 16 -1 (-4675 2950)(-4475 2950);
WIRE 16 -1 (-4475 3050)(-4475 3000);
WIRE 16 -1 (-4675 3000)(-4475 3000);
WIRE 16 -1 (-4475 3100)(-4475 3050);
WIRE 16 -1 (-4675 3050)(-4475 3050);
WIRE 16 -1 (-4475 3150)(-4475 3100);
WIRE 16 -1 (-4675 3100)(-4475 3100);
WIRE 16 -1 (-4475 3200)(-4475 3150);
WIRE 16 -1 (-4675 3150)(-4475 3150);
WIRE 16 -1 (-4475 3250)(-4475 3200);
WIRE 16 -1 (-4675 3200)(-4475 3200);
WIRE 16 -1 (-4475 3300)(-4475 3250);
WIRE 16 -1 (-4675 3250)(-4475 3250);
WIRE 16 -1 (-4475 3350)(-4475 3300);
WIRE 16 -1 (-4675 3300)(-4475 3300);
WIRE 16 -1 (-4475 3400)(-4475 3350);
WIRE 16 -1 (-4675 3350)(-4475 3350);
WIRE 16 -1 (-4475 3450)(-4475 3400);
WIRE 16 -1 (-4675 3400)(-4475 3400);
WIRE 16 -1 (-4475 3500)(-4475 3450);
WIRE 16 -1 (-4675 3450)(-4475 3450);
WIRE 16 -1 (-4475 3550)(-4475 3500);
WIRE 16 -1 (-4675 3500)(-4475 3500);
WIRE 16 -1 (-4475 3600)(-4475 3550);
WIRE 16 -1 (-4675 3550)(-4475 3550);
WIRE 16 -1 (-4475 3650)(-4475 3600);
WIRE 16 -1 (-4675 3600)(-4475 3600);
WIRE 16 -1 (-4475 3700)(-4475 3650);
WIRE 16 -1 (-4675 3650)(-4475 3650);
WIRE 16 -1 (-4475 3750)(-4475 3700);
WIRE 16 -1 (-4675 3700)(-4475 3700);
WIRE 16 -1 (-4475 3800)(-4475 3750);
WIRE 16 -1 (-4675 3750)(-4475 3750);
WIRE 16 -1 (-4475 3850)(-4475 3800);
WIRE 16 -1 (-4675 3800)(-4475 3800);
WIRE 16 -1 (-4475 3900)(-4475 3850);
WIRE 16 -1 (-4675 3850)(-4475 3850);
WIRE 16 -1 (-4475 3950)(-4475 3900);
WIRE 16 -1 (-4675 3900)(-4475 3900);
WIRE 16 -1 (-4475 4000)(-4475 3950);
WIRE 16 -1 (-4675 3950)(-4475 3950);
WIRE 16 -1 (-4475 4050)(-4475 4000);
WIRE 16 -1 (-4675 4000)(-4475 4000);
WIRE 16 -1 (-4475 4100)(-4475 4050);
WIRE 16 -1 (-4675 4050)(-4475 4050);
WIRE 16 -1 (-4475 4150)(-4475 4100);
WIRE 16 -1 (-4675 4100)(-4475 4100);
WIRE 16 -1 (-4475 4200)(-4475 4150);
WIRE 16 -1 (-4675 4150)(-4475 4150);
WIRE 16 -1 (-4475 4250)(-4475 4200);
WIRE 16 -1 (-4675 4200)(-4475 4200);
WIRE 16 -1 (-4475 4300)(-4475 4250);
WIRE 16 -1 (-4675 4250)(-4475 4250);
WIRE 16 -1 (-4475 4350)(-4475 4300);
WIRE 16 -1 (-4675 4300)(-4475 4300);
WIRE 16 -1 (-4475 4400)(-4475 4350);
WIRE 16 -1 (-4675 4350)(-4475 4350);
WIRE 16 -1 (-4475 4450)(-4475 4400);
WIRE 16 -1 (-4675 4400)(-4475 4400);
WIRE 16 -1 (-4475 4500)(-4475 4450);
WIRE 16 -1 (-4675 4450)(-4475 4450);
WIRE 16 -1 (-4475 4550)(-4475 4500);
WIRE 16 -1 (-4675 4500)(-4475 4500);
WIRE 16 -1 (-4475 4600)(-4475 4550);
WIRE 16 -1 (-4675 4550)(-4475 4550);
WIRE 16 -1 (-4475 4650)(-4475 4600);
WIRE 16 -1 (-4675 4600)(-4475 4600);
WIRE 16 -1 (-4675 4650)(-4475 4650);
WIRE 16 -1 (-2800 700)(-2800 575);
WIRE 16 -1 (-2800 750)(-2800 700);
WIRE 16 -1 (-2975 700)(-2800 700);
WIRE 16 -1 (-2800 800)(-2800 750);
WIRE 16 -1 (-2975 750)(-2800 750);
WIRE 16 -1 (-2800 850)(-2800 800);
WIRE 16 -1 (-2975 800)(-2800 800);
WIRE 16 -1 (-2800 900)(-2800 850);
WIRE 16 -1 (-2975 850)(-2800 850);
WIRE 16 -1 (-2800 950)(-2800 900);
WIRE 16 -1 (-2975 900)(-2800 900);
WIRE 16 -1 (-2800 1000)(-2800 950);
WIRE 16 -1 (-2975 950)(-2800 950);
WIRE 16 -1 (-2800 1050)(-2800 1000);
WIRE 16 -1 (-2975 1000)(-2800 1000);
WIRE 16 -1 (-2800 1100)(-2800 1050);
WIRE 16 -1 (-2975 1050)(-2800 1050);
WIRE 16 -1 (-2800 1150)(-2800 1100);
WIRE 16 -1 (-2975 1100)(-2800 1100);
WIRE 16 -1 (-2800 1200)(-2800 1150);
WIRE 16 -1 (-2975 1150)(-2800 1150);
WIRE 16 -1 (-2800 1250)(-2800 1200);
WIRE 16 -1 (-2975 1200)(-2800 1200);
WIRE 16 -1 (-2800 1300)(-2800 1250);
WIRE 16 -1 (-2975 1250)(-2800 1250);
WIRE 16 -1 (-2800 1350)(-2800 1300);
WIRE 16 -1 (-2975 1300)(-2800 1300);
WIRE 16 -1 (-2800 1400)(-2800 1350);
WIRE 16 -1 (-2975 1350)(-2800 1350);
WIRE 16 -1 (-2800 1450)(-2800 1400);
WIRE 16 -1 (-2975 1400)(-2800 1400);
WIRE 16 -1 (-2800 1500)(-2800 1450);
WIRE 16 -1 (-2975 1450)(-2800 1450);
WIRE 16 -1 (-2800 1550)(-2800 1500);
WIRE 16 -1 (-2975 1500)(-2800 1500);
WIRE 16 -1 (-2800 1600)(-2800 1550);
WIRE 16 -1 (-2975 1550)(-2800 1550);
WIRE 16 -1 (-2800 1650)(-2800 1600);
WIRE 16 -1 (-2975 1600)(-2800 1600);
WIRE 16 -1 (-2800 1700)(-2800 1650);
WIRE 16 -1 (-2975 1650)(-2800 1650);
WIRE 16 -1 (-2800 1750)(-2800 1700);
WIRE 16 -1 (-2975 1700)(-2800 1700);
WIRE 16 -1 (-2800 1800)(-2800 1750);
WIRE 16 -1 (-2975 1750)(-2800 1750);
WIRE 16 -1 (-2800 1850)(-2800 1800);
WIRE 16 -1 (-2975 1800)(-2800 1800);
WIRE 16 -1 (-2800 1900)(-2800 1850);
WIRE 16 -1 (-2975 1850)(-2800 1850);
WIRE 16 -1 (-2800 1950)(-2800 1900);
WIRE 16 -1 (-2975 1900)(-2800 1900);
WIRE 16 -1 (-2800 2000)(-2800 1950);
WIRE 16 -1 (-2975 1950)(-2800 1950);
WIRE 16 -1 (-2800 2050)(-2800 2000);
WIRE 16 -1 (-2975 2000)(-2800 2000);
WIRE 16 -1 (-2800 2100)(-2800 2050);
WIRE 16 -1 (-2975 2050)(-2800 2050);
WIRE 16 -1 (-2800 2150)(-2800 2100);
WIRE 16 -1 (-2975 2100)(-2800 2100);
WIRE 16 -1 (-2800 2200)(-2800 2150);
WIRE 16 -1 (-2975 2150)(-2800 2150);
WIRE 16 -1 (-2800 2250)(-2800 2200);
WIRE 16 -1 (-2975 2200)(-2800 2200);
WIRE 16 -1 (-2800 2300)(-2800 2250);
WIRE 16 -1 (-2975 2250)(-2800 2250);
WIRE 16 -1 (-2800 2350)(-2800 2300);
WIRE 16 -1 (-2975 2300)(-2800 2300);
WIRE 16 -1 (-2800 2400)(-2800 2350);
WIRE 16 -1 (-2975 2350)(-2800 2350);
WIRE 16 -1 (-2800 2450)(-2800 2400);
WIRE 16 -1 (-2975 2400)(-2800 2400);
WIRE 16 -1 (-2800 2500)(-2800 2450);
WIRE 16 -1 (-2975 2450)(-2800 2450);
WIRE 16 -1 (-2800 2550)(-2800 2500);
WIRE 16 -1 (-2975 2500)(-2800 2500);
WIRE 16 -1 (-2800 2600)(-2800 2550);
WIRE 16 -1 (-2975 2550)(-2800 2550);
WIRE 16 -1 (-2800 2650)(-2800 2600);
WIRE 16 -1 (-2975 2600)(-2800 2600);
WIRE 16 -1 (-2800 2700)(-2800 2650);
WIRE 16 -1 (-2975 2650)(-2800 2650);
WIRE 16 -1 (-2800 2750)(-2800 2700);
WIRE 16 -1 (-2975 2700)(-2800 2700);
WIRE 16 -1 (-2800 2800)(-2800 2750);
WIRE 16 -1 (-2975 2750)(-2800 2750);
WIRE 16 -1 (-2800 2850)(-2800 2800);
WIRE 16 -1 (-2975 2800)(-2800 2800);
WIRE 16 -1 (-2800 2900)(-2800 2850);
WIRE 16 -1 (-2975 2850)(-2800 2850);
WIRE 16 -1 (-2800 2950)(-2800 2900);
WIRE 16 -1 (-2975 2900)(-2800 2900);
WIRE 16 -1 (-2800 3000)(-2800 2950);
WIRE 16 -1 (-2975 2950)(-2800 2950);
WIRE 16 -1 (-2800 3050)(-2800 3000);
WIRE 16 -1 (-2975 3000)(-2800 3000);
WIRE 16 -1 (-2800 3100)(-2800 3050);
WIRE 16 -1 (-2975 3050)(-2800 3050);
WIRE 16 -1 (-2800 3150)(-2800 3100);
WIRE 16 -1 (-2975 3100)(-2800 3100);
WIRE 16 -1 (-2800 3200)(-2800 3150);
WIRE 16 -1 (-2975 3150)(-2800 3150);
WIRE 16 -1 (-2800 3250)(-2800 3200);
WIRE 16 -1 (-2975 3200)(-2800 3200);
WIRE 16 -1 (-2800 3300)(-2800 3250);
WIRE 16 -1 (-2975 3250)(-2800 3250);
WIRE 16 -1 (-2800 3350)(-2800 3300);
WIRE 16 -1 (-2975 3300)(-2800 3300);
WIRE 16 -1 (-2800 3400)(-2800 3350);
WIRE 16 -1 (-2975 3350)(-2800 3350);
WIRE 16 -1 (-2800 3450)(-2800 3400);
WIRE 16 -1 (-2975 3400)(-2800 3400);
WIRE 16 -1 (-2800 3500)(-2800 3450);
WIRE 16 -1 (-2975 3450)(-2800 3450);
WIRE 16 -1 (-2800 3550)(-2800 3500);
WIRE 16 -1 (-2975 3500)(-2800 3500);
WIRE 16 -1 (-2800 3600)(-2800 3550);
WIRE 16 -1 (-2975 3550)(-2800 3550);
WIRE 16 -1 (-2800 3650)(-2800 3600);
WIRE 16 -1 (-2975 3600)(-2800 3600);
WIRE 16 -1 (-2800 3700)(-2800 3650);
WIRE 16 -1 (-2975 3650)(-2800 3650);
WIRE 16 -1 (-2800 3750)(-2800 3700);
WIRE 16 -1 (-2975 3700)(-2800 3700);
WIRE 16 -1 (-2800 3800)(-2800 3750);
WIRE 16 -1 (-2975 3750)(-2800 3750);
WIRE 16 -1 (-2800 3850)(-2800 3800);
WIRE 16 -1 (-2975 3800)(-2800 3800);
WIRE 16 -1 (-2800 3900)(-2800 3850);
WIRE 16 -1 (-2975 3850)(-2800 3850);
WIRE 16 -1 (-2800 3950)(-2800 3900);
WIRE 16 -1 (-2975 3900)(-2800 3900);
WIRE 16 -1 (-2800 4000)(-2800 3950);
WIRE 16 -1 (-2975 3950)(-2800 3950);
WIRE 16 -1 (-2800 4050)(-2800 4000);
WIRE 16 -1 (-2975 4000)(-2800 4000);
WIRE 16 -1 (-2800 4100)(-2800 4050);
WIRE 16 -1 (-2975 4050)(-2800 4050);
WIRE 16 -1 (-2800 4150)(-2800 4100);
WIRE 16 -1 (-2975 4100)(-2800 4100);
WIRE 16 -1 (-2800 4200)(-2800 4150);
WIRE 16 -1 (-2975 4150)(-2800 4150);
WIRE 16 -1 (-2800 4250)(-2800 4200);
WIRE 16 -1 (-2975 4200)(-2800 4200);
WIRE 16 -1 (-2800 4300)(-2800 4250);
WIRE 16 -1 (-2975 4250)(-2800 4250);
WIRE 16 -1 (-2800 4350)(-2800 4300);
WIRE 16 -1 (-2975 4300)(-2800 4300);
WIRE 16 -1 (-2800 4400)(-2800 4350);
WIRE 16 -1 (-2975 4350)(-2800 4350);
WIRE 16 -1 (-2800 4450)(-2800 4400);
WIRE 16 -1 (-2975 4400)(-2800 4400);
WIRE 16 -1 (-2800 4500)(-2800 4450);
WIRE 16 -1 (-2975 4450)(-2800 4450);
WIRE 16 -1 (-2800 4550)(-2800 4500);
WIRE 16 -1 (-2975 4500)(-2800 4500);
WIRE 16 -1 (-2800 4600)(-2800 4550);
WIRE 16 -1 (-2975 4550)(-2800 4550);
WIRE 16 -1 (-2800 4650)(-2800 4600);
WIRE 16 -1 (-2975 4600)(-2800 4600);
WIRE 16 -1 (-2975 4650)(-2800 4650);
WIRE 16 -1 (-1075 650)(-1075 525);
WIRE 16 -1 (-1075 700)(-1075 650);
WIRE 16 -1 (-1250 650)(-1075 650);
WIRE 16 -1 (-1075 750)(-1075 700);
WIRE 16 -1 (-1250 700)(-1075 700);
WIRE 16 -1 (-1075 800)(-1075 750);
WIRE 16 -1 (-1250 750)(-1075 750);
WIRE 16 -1 (-1075 850)(-1075 800);
WIRE 16 -1 (-1250 800)(-1075 800);
WIRE 16 -1 (-1075 900)(-1075 850);
WIRE 16 -1 (-1250 850)(-1075 850);
WIRE 16 -1 (-1075 950)(-1075 900);
WIRE 16 -1 (-1250 900)(-1075 900);
WIRE 16 -1 (-1075 1000)(-1075 950);
WIRE 16 -1 (-1250 950)(-1075 950);
WIRE 16 -1 (-1075 1050)(-1075 1000);
WIRE 16 -1 (-1250 1000)(-1075 1000);
WIRE 16 -1 (-1075 1100)(-1075 1050);
WIRE 16 -1 (-1250 1050)(-1075 1050);
WIRE 16 -1 (-1075 1150)(-1075 1100);
WIRE 16 -1 (-1250 1100)(-1075 1100);
WIRE 16 -1 (-1075 1200)(-1075 1150);
WIRE 16 -1 (-1250 1150)(-1075 1150);
WIRE 16 -1 (-1075 1250)(-1075 1200);
WIRE 16 -1 (-1250 1200)(-1075 1200);
WIRE 16 -1 (-1075 1300)(-1075 1250);
WIRE 16 -1 (-1250 1250)(-1075 1250);
WIRE 16 -1 (-1075 1350)(-1075 1300);
WIRE 16 -1 (-1250 1300)(-1075 1300);
WIRE 16 -1 (-1075 1400)(-1075 1350);
WIRE 16 -1 (-1250 1350)(-1075 1350);
WIRE 16 -1 (-1075 1450)(-1075 1400);
WIRE 16 -1 (-1250 1400)(-1075 1400);
WIRE 16 -1 (-1075 1500)(-1075 1450);
WIRE 16 -1 (-1250 1450)(-1075 1450);
WIRE 16 -1 (-1075 1550)(-1075 1500);
WIRE 16 -1 (-1250 1500)(-1075 1500);
WIRE 16 -1 (-1075 1600)(-1075 1550);
WIRE 16 -1 (-1250 1550)(-1075 1550);
WIRE 16 -1 (-1075 1650)(-1075 1600);
WIRE 16 -1 (-1250 1600)(-1075 1600);
WIRE 16 -1 (-1075 1700)(-1075 1650);
WIRE 16 -1 (-1250 1650)(-1075 1650);
WIRE 16 -1 (-1075 1750)(-1075 1700);
WIRE 16 -1 (-1250 1700)(-1075 1700);
WIRE 16 -1 (-1075 1800)(-1075 1750);
WIRE 16 -1 (-1250 1750)(-1075 1750);
WIRE 16 -1 (-1075 1850)(-1075 1800);
WIRE 16 -1 (-1250 1800)(-1075 1800);
WIRE 16 -1 (-1075 1900)(-1075 1850);
WIRE 16 -1 (-1250 1850)(-1075 1850);
WIRE 16 -1 (-1075 1950)(-1075 1900);
WIRE 16 -1 (-1250 1900)(-1075 1900);
WIRE 16 -1 (-1075 2000)(-1075 1950);
WIRE 16 -1 (-1250 1950)(-1075 1950);
WIRE 16 -1 (-1075 2050)(-1075 2000);
WIRE 16 -1 (-1250 2000)(-1075 2000);
WIRE 16 -1 (-1075 2100)(-1075 2050);
WIRE 16 -1 (-1250 2050)(-1075 2050);
WIRE 16 -1 (-1075 2150)(-1075 2100);
WIRE 16 -1 (-1250 2100)(-1075 2100);
WIRE 16 -1 (-1075 2200)(-1075 2150);
WIRE 16 -1 (-1250 2150)(-1075 2150);
WIRE 16 -1 (-1075 2250)(-1075 2200);
WIRE 16 -1 (-1250 2200)(-1075 2200);
WIRE 16 -1 (-1075 2300)(-1075 2250);
WIRE 16 -1 (-1250 2250)(-1075 2250);
WIRE 16 -1 (-1075 2350)(-1075 2300);
WIRE 16 -1 (-1250 2300)(-1075 2300);
WIRE 16 -1 (-1075 2400)(-1075 2350);
WIRE 16 -1 (-1250 2350)(-1075 2350);
WIRE 16 -1 (-1075 2450)(-1075 2400);
WIRE 16 -1 (-1250 2400)(-1075 2400);
WIRE 16 -1 (-1075 2500)(-1075 2450);
WIRE 16 -1 (-1250 2450)(-1075 2450);
WIRE 16 -1 (-1075 2550)(-1075 2500);
WIRE 16 -1 (-1250 2500)(-1075 2500);
WIRE 16 -1 (-1075 2600)(-1075 2550);
WIRE 16 -1 (-1250 2550)(-1075 2550);
WIRE 16 -1 (-1075 2650)(-1075 2600);
WIRE 16 -1 (-1250 2600)(-1075 2600);
WIRE 16 -1 (-1075 2700)(-1075 2650);
WIRE 16 -1 (-1250 2650)(-1075 2650);
WIRE 16 -1 (-1075 2750)(-1075 2700);
WIRE 16 -1 (-1250 2700)(-1075 2700);
WIRE 16 -1 (-1075 2800)(-1075 2750);
WIRE 16 -1 (-1250 2750)(-1075 2750);
WIRE 16 -1 (-1075 2850)(-1075 2800);
WIRE 16 -1 (-1250 2800)(-1075 2800);
WIRE 16 -1 (-1075 2900)(-1075 2850);
WIRE 16 -1 (-1250 2850)(-1075 2850);
WIRE 16 -1 (-1075 2950)(-1075 2900);
WIRE 16 -1 (-1250 2900)(-1075 2900);
WIRE 16 -1 (-1075 3000)(-1075 2950);
WIRE 16 -1 (-1250 2950)(-1075 2950);
WIRE 16 -1 (-1075 3050)(-1075 3000);
WIRE 16 -1 (-1250 3000)(-1075 3000);
WIRE 16 -1 (-1075 3100)(-1075 3050);
WIRE 16 -1 (-1250 3050)(-1075 3050);
WIRE 16 -1 (-1075 3150)(-1075 3100);
WIRE 16 -1 (-1250 3100)(-1075 3100);
WIRE 16 -1 (-1075 3200)(-1075 3150);
WIRE 16 -1 (-1250 3150)(-1075 3150);
WIRE 16 -1 (-1075 3250)(-1075 3200);
WIRE 16 -1 (-1250 3200)(-1075 3200);
WIRE 16 -1 (-1075 3300)(-1075 3250);
WIRE 16 -1 (-1250 3250)(-1075 3250);
WIRE 16 -1 (-1075 3350)(-1075 3300);
WIRE 16 -1 (-1250 3300)(-1075 3300);
WIRE 16 -1 (-1075 3400)(-1075 3350);
WIRE 16 -1 (-1250 3350)(-1075 3350);
WIRE 16 -1 (-1075 3450)(-1075 3400);
WIRE 16 -1 (-1250 3400)(-1075 3400);
WIRE 16 -1 (-1075 3500)(-1075 3450);
WIRE 16 -1 (-1250 3450)(-1075 3450);
WIRE 16 -1 (-1075 3550)(-1075 3500);
WIRE 16 -1 (-1250 3500)(-1075 3500);
WIRE 16 -1 (-1075 3600)(-1075 3550);
WIRE 16 -1 (-1250 3550)(-1075 3550);
WIRE 16 -1 (-1075 3650)(-1075 3600);
WIRE 16 -1 (-1250 3600)(-1075 3600);
WIRE 16 -1 (-1075 3700)(-1075 3650);
WIRE 16 -1 (-1250 3650)(-1075 3650);
WIRE 16 -1 (-1075 3750)(-1075 3700);
WIRE 16 -1 (-1250 3700)(-1075 3700);
WIRE 16 -1 (-1075 3800)(-1075 3750);
WIRE 16 -1 (-1250 3750)(-1075 3750);
WIRE 16 -1 (-1075 3850)(-1075 3800);
WIRE 16 -1 (-1250 3800)(-1075 3800);
WIRE 16 -1 (-1075 3900)(-1075 3850);
WIRE 16 -1 (-1250 3850)(-1075 3850);
WIRE 16 -1 (-1075 3950)(-1075 3900);
WIRE 16 -1 (-1250 3900)(-1075 3900);
WIRE 16 -1 (-1075 4000)(-1075 3950);
WIRE 16 -1 (-1250 3950)(-1075 3950);
WIRE 16 -1 (-1075 4050)(-1075 4000);
WIRE 16 -1 (-1250 4000)(-1075 4000);
WIRE 16 -1 (-1075 4100)(-1075 4050);
WIRE 16 -1 (-1250 4050)(-1075 4050);
WIRE 16 -1 (-1075 4150)(-1075 4100);
WIRE 16 -1 (-1250 4100)(-1075 4100);
WIRE 16 -1 (-1075 4200)(-1075 4150);
WIRE 16 -1 (-1250 4150)(-1075 4150);
WIRE 16 -1 (-1075 4250)(-1075 4200);
WIRE 16 -1 (-1250 4200)(-1075 4200);
WIRE 16 -1 (-1075 4300)(-1075 4250);
WIRE 16 -1 (-1250 4250)(-1075 4250);
WIRE 16 -1 (-1075 4350)(-1075 4300);
WIRE 16 -1 (-1250 4300)(-1075 4300);
WIRE 16 -1 (-1075 4400)(-1075 4350);
WIRE 16 -1 (-1250 4350)(-1075 4350);
WIRE 16 -1 (-1075 4450)(-1075 4400);
WIRE 16 -1 (-1250 4400)(-1075 4400);
WIRE 16 -1 (-1075 4500)(-1075 4450);
WIRE 16 -1 (-1250 4450)(-1075 4450);
WIRE 16 -1 (-1075 4550)(-1075 4500);
WIRE 16 -1 (-1250 4500)(-1075 4500);
WIRE 16 -1 (-1075 4600)(-1075 4550);
WIRE 16 -1 (-1250 4550)(-1075 4550);
WIRE 16 -1 (-1250 4600)(-1075 4600);
WIRE 16 -1 (-6025 700)(-6025 600);
WIRE 16 -1 (-6025 750)(-6025 700);
WIRE 16 -1 (-6025 700)(-5875 700);
WIRE 16 -1 (-6025 800)(-6025 750);
WIRE 16 -1 (-5875 750)(-6025 750);
WIRE 16 -1 (-6025 850)(-6025 800);
WIRE 16 -1 (-5875 800)(-6025 800);
WIRE 16 -1 (-6025 900)(-6025 850);
WIRE 16 -1 (-5875 850)(-6025 850);
WIRE 16 -1 (-6025 950)(-6025 900);
WIRE 16 -1 (-6025 900)(-5875 900);
WIRE 16 -1 (-6025 1000)(-6025 950);
WIRE 16 -1 (-5875 950)(-6025 950);
WIRE 16 -1 (-6025 1050)(-6025 1000);
WIRE 16 -1 (-5875 1000)(-6025 1000);
WIRE 16 -1 (-6025 1100)(-6025 1050);
WIRE 16 -1 (-5875 1050)(-6025 1050);
WIRE 16 -1 (-6025 1150)(-6025 1100);
WIRE 16 -1 (-5875 1100)(-6025 1100);
WIRE 16 -1 (-6025 1200)(-6025 1150);
WIRE 16 -1 (-5875 1150)(-6025 1150);
WIRE 16 -1 (-6025 1250)(-6025 1200);
WIRE 16 -1 (-5875 1200)(-6025 1200);
WIRE 16 -1 (-6025 1300)(-6025 1250);
WIRE 16 -1 (-5875 1250)(-6025 1250);
WIRE 16 -1 (-6025 1350)(-6025 1300);
WIRE 16 -1 (-5875 1300)(-6025 1300);
WIRE 16 -1 (-6025 1400)(-6025 1350);
WIRE 16 -1 (-5875 1350)(-6025 1350);
WIRE 16 -1 (-6025 1450)(-6025 1400);
WIRE 16 -1 (-5875 1400)(-6025 1400);
WIRE 16 -1 (-6025 1500)(-6025 1450);
WIRE 16 -1 (-5875 1450)(-6025 1450);
WIRE 16 -1 (-6025 1550)(-6025 1500);
WIRE 16 -1 (-5875 1500)(-6025 1500);
WIRE 16 -1 (-6025 1600)(-6025 1550);
WIRE 16 -1 (-5875 1550)(-6025 1550);
WIRE 16 -1 (-6025 1650)(-6025 1600);
WIRE 16 -1 (-5875 1600)(-6025 1600);
WIRE 16 -1 (-6025 1700)(-6025 1650);
WIRE 16 -1 (-5875 1650)(-6025 1650);
WIRE 16 -1 (-6025 1750)(-6025 1700);
WIRE 16 -1 (-5875 1700)(-6025 1700);
WIRE 16 -1 (-6025 1800)(-6025 1750);
WIRE 16 -1 (-5875 1750)(-6025 1750);
WIRE 16 -1 (-6025 1850)(-6025 1800);
WIRE 16 -1 (-5875 1800)(-6025 1800);
WIRE 16 -1 (-6025 1900)(-6025 1850);
WIRE 16 -1 (-5875 1850)(-6025 1850);
WIRE 16 -1 (-6025 1950)(-6025 1900);
WIRE 16 -1 (-5875 1900)(-6025 1900);
WIRE 16 -1 (-6025 2000)(-6025 1950);
WIRE 16 -1 (-5875 1950)(-6025 1950);
WIRE 16 -1 (-6025 2050)(-6025 2000);
WIRE 16 -1 (-5875 2000)(-6025 2000);
WIRE 16 -1 (-6025 2100)(-6025 2050);
WIRE 16 -1 (-5875 2050)(-6025 2050);
WIRE 16 -1 (-6025 2150)(-6025 2100);
WIRE 16 -1 (-5875 2100)(-6025 2100);
WIRE 16 -1 (-6025 2200)(-6025 2150);
WIRE 16 -1 (-5875 2150)(-6025 2150);
WIRE 16 -1 (-6025 2250)(-6025 2200);
WIRE 16 -1 (-5875 2200)(-6025 2200);
WIRE 16 -1 (-6025 2300)(-6025 2250);
WIRE 16 -1 (-5875 2250)(-6025 2250);
WIRE 16 -1 (-6025 2350)(-6025 2300);
WIRE 16 -1 (-5875 2300)(-6025 2300);
WIRE 16 -1 (-6025 2400)(-6025 2350);
WIRE 16 -1 (-5875 2350)(-6025 2350);
WIRE 16 -1 (-6025 2450)(-6025 2400);
WIRE 16 -1 (-5875 2400)(-6025 2400);
WIRE 16 -1 (-6025 2500)(-6025 2450);
WIRE 16 -1 (-5875 2450)(-6025 2450);
WIRE 16 -1 (-6025 2550)(-6025 2500);
WIRE 16 -1 (-5875 2500)(-6025 2500);
WIRE 16 -1 (-6025 2600)(-6025 2550);
WIRE 16 -1 (-5875 2550)(-6025 2550);
WIRE 16 -1 (-6025 2650)(-6025 2600);
WIRE 16 -1 (-5875 2600)(-6025 2600);
WIRE 16 -1 (-6025 2700)(-6025 2650);
WIRE 16 -1 (-5875 2650)(-6025 2650);
WIRE 16 -1 (-6025 2750)(-6025 2700);
WIRE 16 -1 (-5875 2700)(-6025 2700);
WIRE 16 -1 (-6025 2800)(-6025 2750);
WIRE 16 -1 (-5875 2750)(-6025 2750);
WIRE 16 -1 (-6025 2850)(-6025 2800);
WIRE 16 -1 (-5875 2800)(-6025 2800);
WIRE 16 -1 (-6025 2900)(-6025 2850);
WIRE 16 -1 (-5875 2850)(-6025 2850);
WIRE 16 -1 (-6025 2950)(-6025 2900);
WIRE 16 -1 (-5875 2900)(-6025 2900);
WIRE 16 -1 (-6025 3000)(-6025 2950);
WIRE 16 -1 (-5875 2950)(-6025 2950);
WIRE 16 -1 (-6025 3050)(-6025 3000);
WIRE 16 -1 (-5875 3000)(-6025 3000);
WIRE 16 -1 (-6025 3100)(-6025 3050);
WIRE 16 -1 (-5875 3050)(-6025 3050);
WIRE 16 -1 (-6025 3150)(-6025 3100);
WIRE 16 -1 (-5875 3100)(-6025 3100);
WIRE 16 -1 (-6025 3200)(-6025 3150);
WIRE 16 -1 (-5875 3150)(-6025 3150);
WIRE 16 -1 (-6025 3250)(-6025 3200);
WIRE 16 -1 (-5875 3200)(-6025 3200);
WIRE 16 -1 (-6025 3300)(-6025 3250);
WIRE 16 -1 (-5875 3250)(-6025 3250);
WIRE 16 -1 (-6025 3350)(-6025 3300);
WIRE 16 -1 (-5875 3300)(-6025 3300);
WIRE 16 -1 (-6025 3400)(-6025 3350);
WIRE 16 -1 (-5875 3350)(-6025 3350);
WIRE 16 -1 (-6025 3450)(-6025 3400);
WIRE 16 -1 (-5875 3400)(-6025 3400);
WIRE 16 -1 (-6025 3500)(-6025 3450);
WIRE 16 -1 (-5875 3450)(-6025 3450);
WIRE 16 -1 (-6025 3550)(-6025 3500);
WIRE 16 -1 (-5875 3500)(-6025 3500);
WIRE 16 -1 (-6025 3600)(-6025 3550);
WIRE 16 -1 (-5875 3550)(-6025 3550);
WIRE 16 -1 (-6025 3650)(-6025 3600);
WIRE 16 -1 (-5875 3600)(-6025 3600);
WIRE 16 -1 (-6025 3700)(-6025 3650);
WIRE 16 -1 (-5875 3650)(-6025 3650);
WIRE 16 -1 (-6025 3750)(-6025 3700);
WIRE 16 -1 (-5875 3700)(-6025 3700);
WIRE 16 -1 (-6025 3800)(-6025 3750);
WIRE 16 -1 (-5875 3750)(-6025 3750);
WIRE 16 -1 (-6025 3850)(-6025 3800);
WIRE 16 -1 (-5875 3800)(-6025 3800);
WIRE 16 -1 (-6025 3900)(-6025 3850);
WIRE 16 -1 (-5875 3850)(-6025 3850);
WIRE 16 -1 (-6025 3950)(-6025 3900);
WIRE 16 -1 (-5875 3900)(-6025 3900);
WIRE 16 -1 (-6025 4000)(-6025 3950);
WIRE 16 -1 (-5875 3950)(-6025 3950);
WIRE 16 -1 (-6025 4050)(-6025 4000);
WIRE 16 -1 (-5875 4000)(-6025 4000);
WIRE 16 -1 (-6025 4100)(-6025 4050);
WIRE 16 -1 (-5875 4050)(-6025 4050);
WIRE 16 -1 (-6025 4150)(-6025 4100);
WIRE 16 -1 (-5875 4100)(-6025 4100);
WIRE 16 -1 (-6025 4200)(-6025 4150);
WIRE 16 -1 (-5875 4150)(-6025 4150);
WIRE 16 -1 (-6025 4250)(-6025 4200);
WIRE 16 -1 (-5875 4200)(-6025 4200);
WIRE 16 -1 (-6025 4300)(-6025 4250);
WIRE 16 -1 (-5875 4250)(-6025 4250);
WIRE 16 -1 (-6025 4350)(-6025 4300);
WIRE 16 -1 (-5875 4300)(-6025 4300);
WIRE 16 -1 (-6025 4400)(-6025 4350);
WIRE 16 -1 (-5875 4350)(-6025 4350);
WIRE 16 -1 (-6025 4450)(-6025 4400);
WIRE 16 -1 (-5875 4400)(-6025 4400);
WIRE 16 -1 (-6025 4500)(-6025 4450);
WIRE 16 -1 (-5875 4450)(-6025 4450);
WIRE 16 -1 (-6025 4550)(-6025 4500);
WIRE 16 -1 (-5875 4500)(-6025 4500);
WIRE 16 -1 (-6025 4600)(-6025 4550);
WIRE 16 -1 (-5875 4550)(-6025 4550);
WIRE 16 -1 (-6025 4650)(-6025 4600);
WIRE 16 -1 (-5875 4600)(-6025 4600);
WIRE 16 -1 (-5875 4650)(-6025 4650);
WIRE 16 -1 (-4350 700)(-4350 600);
WIRE 16 -1 (-4350 750)(-4350 700);
WIRE 16 -1 (-4350 700)(-4175 700);
WIRE 16 -1 (-4350 800)(-4350 750);
WIRE 16 -1 (-4175 750)(-4350 750);
WIRE 16 -1 (-4350 850)(-4350 800);
WIRE 16 -1 (-4175 800)(-4350 800);
WIRE 16 -1 (-4350 900)(-4350 850);
WIRE 16 -1 (-4175 850)(-4350 850);
WIRE 16 -1 (-4350 950)(-4350 900);
WIRE 16 -1 (-4350 900)(-4175 900);
WIRE 16 -1 (-4350 1000)(-4350 950);
WIRE 16 -1 (-4175 950)(-4350 950);
WIRE 16 -1 (-4350 1050)(-4350 1000);
WIRE 16 -1 (-4175 1000)(-4350 1000);
WIRE 16 -1 (-4350 1100)(-4350 1050);
WIRE 16 -1 (-4175 1050)(-4350 1050);
WIRE 16 -1 (-4350 1150)(-4350 1100);
WIRE 16 -1 (-4175 1100)(-4350 1100);
WIRE 16 -1 (-4350 1200)(-4350 1150);
WIRE 16 -1 (-4175 1150)(-4350 1150);
WIRE 16 -1 (-4350 1250)(-4350 1200);
WIRE 16 -1 (-4175 1200)(-4350 1200);
WIRE 16 -1 (-4350 1300)(-4350 1250);
WIRE 16 -1 (-4175 1250)(-4350 1250);
WIRE 16 -1 (-4350 1350)(-4350 1300);
WIRE 16 -1 (-4175 1300)(-4350 1300);
WIRE 16 -1 (-4350 1400)(-4350 1350);
WIRE 16 -1 (-4175 1350)(-4350 1350);
WIRE 16 -1 (-4350 1450)(-4350 1400);
WIRE 16 -1 (-4175 1400)(-4350 1400);
WIRE 16 -1 (-4350 1500)(-4350 1450);
WIRE 16 -1 (-4175 1450)(-4350 1450);
WIRE 16 -1 (-4350 1550)(-4350 1500);
WIRE 16 -1 (-4175 1500)(-4350 1500);
WIRE 16 -1 (-4350 1600)(-4350 1550);
WIRE 16 -1 (-4175 1550)(-4350 1550);
WIRE 16 -1 (-4350 1650)(-4350 1600);
WIRE 16 -1 (-4175 1600)(-4350 1600);
WIRE 16 -1 (-4350 1700)(-4350 1650);
WIRE 16 -1 (-4175 1650)(-4350 1650);
WIRE 16 -1 (-4350 1750)(-4350 1700);
WIRE 16 -1 (-4175 1700)(-4350 1700);
WIRE 16 -1 (-4350 1800)(-4350 1750);
WIRE 16 -1 (-4175 1750)(-4350 1750);
WIRE 16 -1 (-4350 1850)(-4350 1800);
WIRE 16 -1 (-4175 1800)(-4350 1800);
WIRE 16 -1 (-4350 1900)(-4350 1850);
WIRE 16 -1 (-4175 1850)(-4350 1850);
WIRE 16 -1 (-4350 1950)(-4350 1900);
WIRE 16 -1 (-4175 1900)(-4350 1900);
WIRE 16 -1 (-4350 2000)(-4350 1950);
WIRE 16 -1 (-4175 1950)(-4350 1950);
WIRE 16 -1 (-4350 2050)(-4350 2000);
WIRE 16 -1 (-4175 2000)(-4350 2000);
WIRE 16 -1 (-4350 2100)(-4350 2050);
WIRE 16 -1 (-4175 2050)(-4350 2050);
WIRE 16 -1 (-4350 2150)(-4350 2100);
WIRE 16 -1 (-4175 2100)(-4350 2100);
WIRE 16 -1 (-4350 2200)(-4350 2150);
WIRE 16 -1 (-4175 2150)(-4350 2150);
WIRE 16 -1 (-4350 2250)(-4350 2200);
WIRE 16 -1 (-4175 2200)(-4350 2200);
WIRE 16 -1 (-4350 2300)(-4350 2250);
WIRE 16 -1 (-4175 2250)(-4350 2250);
WIRE 16 -1 (-4350 2350)(-4350 2300);
WIRE 16 -1 (-4175 2300)(-4350 2300);
WIRE 16 -1 (-4350 2400)(-4350 2350);
WIRE 16 -1 (-4175 2350)(-4350 2350);
WIRE 16 -1 (-4350 2450)(-4350 2400);
WIRE 16 -1 (-4175 2400)(-4350 2400);
WIRE 16 -1 (-4350 2500)(-4350 2450);
WIRE 16 -1 (-4175 2450)(-4350 2450);
WIRE 16 -1 (-4350 2550)(-4350 2500);
WIRE 16 -1 (-4175 2500)(-4350 2500);
WIRE 16 -1 (-4350 2600)(-4350 2550);
WIRE 16 -1 (-4175 2550)(-4350 2550);
WIRE 16 -1 (-4350 2650)(-4350 2600);
WIRE 16 -1 (-4175 2600)(-4350 2600);
WIRE 16 -1 (-4350 2700)(-4350 2650);
WIRE 16 -1 (-4175 2650)(-4350 2650);
WIRE 16 -1 (-4350 2750)(-4350 2700);
WIRE 16 -1 (-4175 2700)(-4350 2700);
WIRE 16 -1 (-4350 2800)(-4350 2750);
WIRE 16 -1 (-4175 2750)(-4350 2750);
WIRE 16 -1 (-4350 2850)(-4350 2800);
WIRE 16 -1 (-4175 2800)(-4350 2800);
WIRE 16 -1 (-4350 2900)(-4350 2850);
WIRE 16 -1 (-4175 2850)(-4350 2850);
WIRE 16 -1 (-4350 2950)(-4350 2900);
WIRE 16 -1 (-4175 2900)(-4350 2900);
WIRE 16 -1 (-4350 3000)(-4350 2950);
WIRE 16 -1 (-4175 2950)(-4350 2950);
WIRE 16 -1 (-4350 3050)(-4350 3000);
WIRE 16 -1 (-4175 3000)(-4350 3000);
WIRE 16 -1 (-4350 3100)(-4350 3050);
WIRE 16 -1 (-4175 3050)(-4350 3050);
WIRE 16 -1 (-4350 3150)(-4350 3100);
WIRE 16 -1 (-4175 3100)(-4350 3100);
WIRE 16 -1 (-4350 3200)(-4350 3150);
WIRE 16 -1 (-4175 3150)(-4350 3150);
WIRE 16 -1 (-4350 3250)(-4350 3200);
WIRE 16 -1 (-4175 3200)(-4350 3200);
WIRE 16 -1 (-4350 3300)(-4350 3250);
WIRE 16 -1 (-4175 3250)(-4350 3250);
WIRE 16 -1 (-4350 3350)(-4350 3300);
WIRE 16 -1 (-4175 3300)(-4350 3300);
WIRE 16 -1 (-4350 3400)(-4350 3350);
WIRE 16 -1 (-4175 3350)(-4350 3350);
WIRE 16 -1 (-4350 3450)(-4350 3400);
WIRE 16 -1 (-4175 3400)(-4350 3400);
WIRE 16 -1 (-4350 3500)(-4350 3450);
WIRE 16 -1 (-4175 3450)(-4350 3450);
WIRE 16 -1 (-4350 3550)(-4350 3500);
WIRE 16 -1 (-4175 3500)(-4350 3500);
WIRE 16 -1 (-4350 3600)(-4350 3550);
WIRE 16 -1 (-4175 3550)(-4350 3550);
WIRE 16 -1 (-4350 3650)(-4350 3600);
WIRE 16 -1 (-4175 3600)(-4350 3600);
WIRE 16 -1 (-4350 3700)(-4350 3650);
WIRE 16 -1 (-4175 3650)(-4350 3650);
WIRE 16 -1 (-4350 3750)(-4350 3700);
WIRE 16 -1 (-4175 3700)(-4350 3700);
WIRE 16 -1 (-4350 3800)(-4350 3750);
WIRE 16 -1 (-4175 3750)(-4350 3750);
WIRE 16 -1 (-4350 3850)(-4350 3800);
WIRE 16 -1 (-4175 3800)(-4350 3800);
WIRE 16 -1 (-4350 3900)(-4350 3850);
WIRE 16 -1 (-4175 3850)(-4350 3850);
WIRE 16 -1 (-4350 3950)(-4350 3900);
WIRE 16 -1 (-4175 3900)(-4350 3900);
WIRE 16 -1 (-4350 4000)(-4350 3950);
WIRE 16 -1 (-4175 3950)(-4350 3950);
WIRE 16 -1 (-4350 4050)(-4350 4000);
WIRE 16 -1 (-4175 4000)(-4350 4000);
WIRE 16 -1 (-4350 4100)(-4350 4050);
WIRE 16 -1 (-4175 4050)(-4350 4050);
WIRE 16 -1 (-4350 4150)(-4350 4100);
WIRE 16 -1 (-4175 4100)(-4350 4100);
WIRE 16 -1 (-4350 4200)(-4350 4150);
WIRE 16 -1 (-4175 4150)(-4350 4150);
WIRE 16 -1 (-4350 4250)(-4350 4200);
WIRE 16 -1 (-4175 4200)(-4350 4200);
WIRE 16 -1 (-4350 4300)(-4350 4250);
WIRE 16 -1 (-4175 4250)(-4350 4250);
WIRE 16 -1 (-4350 4350)(-4350 4300);
WIRE 16 -1 (-4175 4300)(-4350 4300);
WIRE 16 -1 (-4350 4400)(-4350 4350);
WIRE 16 -1 (-4175 4350)(-4350 4350);
WIRE 16 -1 (-4350 4450)(-4350 4400);
WIRE 16 -1 (-4175 4400)(-4350 4400);
WIRE 16 -1 (-4350 4500)(-4350 4450);
WIRE 16 -1 (-4175 4450)(-4350 4450);
WIRE 16 -1 (-4350 4550)(-4350 4500);
WIRE 16 -1 (-4175 4500)(-4350 4500);
WIRE 16 -1 (-4350 4600)(-4350 4550);
WIRE 16 -1 (-4175 4550)(-4350 4550);
WIRE 16 -1 (-4350 4650)(-4350 4600);
WIRE 16 -1 (-4175 4600)(-4350 4600);
WIRE 16 -1 (-4175 4650)(-4350 4650);
WIRE 16 -1 (-2625 650)(-2625 550);
WIRE 16 -1 (-2625 700)(-2625 650);
WIRE 16 -1 (-2625 650)(-2450 650);
WIRE 16 -1 (-2625 750)(-2625 700);
WIRE 16 -1 (-2450 700)(-2625 700);
WIRE 16 -1 (-2625 800)(-2625 750);
WIRE 16 -1 (-2450 750)(-2625 750);
WIRE 16 -1 (-2625 850)(-2625 800);
WIRE 16 -1 (-2450 800)(-2625 800);
WIRE 16 -1 (-2625 900)(-2625 850);
WIRE 16 -1 (-2625 850)(-2450 850);
WIRE 16 -1 (-2625 950)(-2625 900);
WIRE 16 -1 (-2450 900)(-2625 900);
WIRE 16 -1 (-2625 1000)(-2625 950);
WIRE 16 -1 (-2450 950)(-2625 950);
WIRE 16 -1 (-2625 1050)(-2625 1000);
WIRE 16 -1 (-2450 1000)(-2625 1000);
WIRE 16 -1 (-2625 1100)(-2625 1050);
WIRE 16 -1 (-2450 1050)(-2625 1050);
WIRE 16 -1 (-2625 1150)(-2625 1100);
WIRE 16 -1 (-2450 1100)(-2625 1100);
WIRE 16 -1 (-2625 1200)(-2625 1150);
WIRE 16 -1 (-2450 1150)(-2625 1150);
WIRE 16 -1 (-2625 1250)(-2625 1200);
WIRE 16 -1 (-2450 1200)(-2625 1200);
WIRE 16 -1 (-2625 1300)(-2625 1250);
WIRE 16 -1 (-2450 1250)(-2625 1250);
WIRE 16 -1 (-2625 1350)(-2625 1300);
WIRE 16 -1 (-2450 1300)(-2625 1300);
WIRE 16 -1 (-2625 1400)(-2625 1350);
WIRE 16 -1 (-2450 1350)(-2625 1350);
WIRE 16 -1 (-2625 1450)(-2625 1400);
WIRE 16 -1 (-2450 1400)(-2625 1400);
WIRE 16 -1 (-2625 1500)(-2625 1450);
WIRE 16 -1 (-2450 1450)(-2625 1450);
WIRE 16 -1 (-2625 1550)(-2625 1500);
WIRE 16 -1 (-2450 1500)(-2625 1500);
WIRE 16 -1 (-2625 1600)(-2625 1550);
WIRE 16 -1 (-2450 1550)(-2625 1550);
WIRE 16 -1 (-2625 1650)(-2625 1600);
WIRE 16 -1 (-2450 1600)(-2625 1600);
WIRE 16 -1 (-2625 1700)(-2625 1650);
WIRE 16 -1 (-2450 1650)(-2625 1650);
WIRE 16 -1 (-2625 1750)(-2625 1700);
WIRE 16 -1 (-2450 1700)(-2625 1700);
WIRE 16 -1 (-2625 1800)(-2625 1750);
WIRE 16 -1 (-2450 1750)(-2625 1750);
WIRE 16 -1 (-2625 1850)(-2625 1800);
WIRE 16 -1 (-2450 1800)(-2625 1800);
WIRE 16 -1 (-2625 1900)(-2625 1850);
WIRE 16 -1 (-2450 1850)(-2625 1850);
WIRE 16 -1 (-2625 1950)(-2625 1900);
WIRE 16 -1 (-2450 1900)(-2625 1900);
WIRE 16 -1 (-2625 2000)(-2625 1950);
WIRE 16 -1 (-2450 1950)(-2625 1950);
WIRE 16 -1 (-2625 2050)(-2625 2000);
WIRE 16 -1 (-2450 2000)(-2625 2000);
WIRE 16 -1 (-2625 2100)(-2625 2050);
WIRE 16 -1 (-2450 2050)(-2625 2050);
WIRE 16 -1 (-2625 2150)(-2625 2100);
WIRE 16 -1 (-2450 2100)(-2625 2100);
WIRE 16 -1 (-2625 2200)(-2625 2150);
WIRE 16 -1 (-2450 2150)(-2625 2150);
WIRE 16 -1 (-2625 2250)(-2625 2200);
WIRE 16 -1 (-2450 2200)(-2625 2200);
WIRE 16 -1 (-2625 2300)(-2625 2250);
WIRE 16 -1 (-2450 2250)(-2625 2250);
WIRE 16 -1 (-2625 2350)(-2625 2300);
WIRE 16 -1 (-2450 2300)(-2625 2300);
WIRE 16 -1 (-2625 2400)(-2625 2350);
WIRE 16 -1 (-2450 2350)(-2625 2350);
WIRE 16 -1 (-2625 2450)(-2625 2400);
WIRE 16 -1 (-2450 2400)(-2625 2400);
WIRE 16 -1 (-2625 2500)(-2625 2450);
WIRE 16 -1 (-2450 2450)(-2625 2450);
WIRE 16 -1 (-2625 2550)(-2625 2500);
WIRE 16 -1 (-2450 2500)(-2625 2500);
WIRE 16 -1 (-2625 2600)(-2625 2550);
WIRE 16 -1 (-2450 2550)(-2625 2550);
WIRE 16 -1 (-2625 2650)(-2625 2600);
WIRE 16 -1 (-2450 2600)(-2625 2600);
WIRE 16 -1 (-2625 2700)(-2625 2650);
WIRE 16 -1 (-2450 2650)(-2625 2650);
WIRE 16 -1 (-2625 2750)(-2625 2700);
WIRE 16 -1 (-2450 2700)(-2625 2700);
WIRE 16 -1 (-2625 2800)(-2625 2750);
WIRE 16 -1 (-2450 2750)(-2625 2750);
WIRE 16 -1 (-2625 2850)(-2625 2800);
WIRE 16 -1 (-2450 2800)(-2625 2800);
WIRE 16 -1 (-2625 2900)(-2625 2850);
WIRE 16 -1 (-2450 2850)(-2625 2850);
WIRE 16 -1 (-2625 2950)(-2625 2900);
WIRE 16 -1 (-2450 2900)(-2625 2900);
WIRE 16 -1 (-2625 3000)(-2625 2950);
WIRE 16 -1 (-2450 2950)(-2625 2950);
WIRE 16 -1 (-2625 3050)(-2625 3000);
WIRE 16 -1 (-2450 3000)(-2625 3000);
WIRE 16 -1 (-2625 3100)(-2625 3050);
WIRE 16 -1 (-2450 3050)(-2625 3050);
WIRE 16 -1 (-2625 3150)(-2625 3100);
WIRE 16 -1 (-2450 3100)(-2625 3100);
WIRE 16 -1 (-2625 3200)(-2625 3150);
WIRE 16 -1 (-2450 3150)(-2625 3150);
WIRE 16 -1 (-2625 3250)(-2625 3200);
WIRE 16 -1 (-2450 3200)(-2625 3200);
WIRE 16 -1 (-2625 3300)(-2625 3250);
WIRE 16 -1 (-2450 3250)(-2625 3250);
WIRE 16 -1 (-2625 3350)(-2625 3300);
WIRE 16 -1 (-2450 3300)(-2625 3300);
WIRE 16 -1 (-2625 3400)(-2625 3350);
WIRE 16 -1 (-2450 3350)(-2625 3350);
WIRE 16 -1 (-2625 3450)(-2625 3400);
WIRE 16 -1 (-2450 3400)(-2625 3400);
WIRE 16 -1 (-2625 3500)(-2625 3450);
WIRE 16 -1 (-2450 3450)(-2625 3450);
WIRE 16 -1 (-2625 3550)(-2625 3500);
WIRE 16 -1 (-2450 3500)(-2625 3500);
WIRE 16 -1 (-2625 3600)(-2625 3550);
WIRE 16 -1 (-2450 3550)(-2625 3550);
WIRE 16 -1 (-2625 3650)(-2625 3600);
WIRE 16 -1 (-2450 3600)(-2625 3600);
WIRE 16 -1 (-2625 3700)(-2625 3650);
WIRE 16 -1 (-2450 3650)(-2625 3650);
WIRE 16 -1 (-2625 3750)(-2625 3700);
WIRE 16 -1 (-2450 3700)(-2625 3700);
WIRE 16 -1 (-2625 3800)(-2625 3750);
WIRE 16 -1 (-2450 3750)(-2625 3750);
WIRE 16 -1 (-2625 3850)(-2625 3800);
WIRE 16 -1 (-2450 3800)(-2625 3800);
WIRE 16 -1 (-2625 3900)(-2625 3850);
WIRE 16 -1 (-2450 3850)(-2625 3850);
WIRE 16 -1 (-2625 3950)(-2625 3900);
WIRE 16 -1 (-2450 3900)(-2625 3900);
WIRE 16 -1 (-2625 4000)(-2625 3950);
WIRE 16 -1 (-2450 3950)(-2625 3950);
WIRE 16 -1 (-2625 4050)(-2625 4000);
WIRE 16 -1 (-2450 4000)(-2625 4000);
WIRE 16 -1 (-2625 4100)(-2625 4050);
WIRE 16 -1 (-2450 4050)(-2625 4050);
WIRE 16 -1 (-2625 4150)(-2625 4100);
WIRE 16 -1 (-2450 4100)(-2625 4100);
WIRE 16 -1 (-2625 4200)(-2625 4150);
WIRE 16 -1 (-2450 4150)(-2625 4150);
WIRE 16 -1 (-2625 4250)(-2625 4200);
WIRE 16 -1 (-2450 4200)(-2625 4200);
WIRE 16 -1 (-2625 4300)(-2625 4250);
WIRE 16 -1 (-2450 4250)(-2625 4250);
WIRE 16 -1 (-2625 4350)(-2625 4300);
WIRE 16 -1 (-2450 4300)(-2625 4300);
WIRE 16 -1 (-2625 4400)(-2625 4350);
WIRE 16 -1 (-2450 4350)(-2625 4350);
WIRE 16 -1 (-2625 4450)(-2625 4400);
WIRE 16 -1 (-2450 4400)(-2625 4400);
WIRE 16 -1 (-2625 4500)(-2625 4450);
WIRE 16 -1 (-2450 4450)(-2625 4450);
WIRE 16 -1 (-2625 4550)(-2625 4500);
WIRE 16 -1 (-2450 4500)(-2625 4500);
WIRE 16 -1 (-2625 4600)(-2625 4550);
WIRE 16 -1 (-2450 4550)(-2625 4550);
WIRE 16 -1 (-2450 4600)(-2625 4600);
WIRE 16 -1 (-925 525)(-925 700);
WIRE 16 -1 (-925 700)(-925 750);
WIRE 16 -1 (-775 700)(-925 700);
WIRE 16 -1 (-925 750)(-925 800);
WIRE 16 -1 (-775 750)(-925 750);
WIRE 16 -1 (-925 800)(-925 850);
WIRE 16 -1 (-775 800)(-925 800);
WIRE 16 -1 (-925 850)(-925 900);
WIRE 16 -1 (-775 850)(-925 850);
WIRE 16 -1 (-925 900)(-925 950);
WIRE 16 -1 (-775 900)(-925 900);
WIRE 16 -1 (-925 950)(-925 1000);
WIRE 16 -1 (-775 950)(-925 950);
WIRE 16 -1 (-925 1000)(-925 1050);
WIRE 16 -1 (-775 1000)(-925 1000);
WIRE 16 -1 (-925 1050)(-925 1100);
WIRE 16 -1 (-775 1050)(-925 1050);
WIRE 16 -1 (-925 1100)(-925 1150);
WIRE 16 -1 (-775 1100)(-925 1100);
WIRE 16 -1 (-925 1150)(-925 1200);
WIRE 16 -1 (-775 1150)(-925 1150);
WIRE 16 -1 (-925 1200)(-925 1250);
WIRE 16 -1 (-775 1200)(-925 1200);
WIRE 16 -1 (-925 1250)(-925 1300);
WIRE 16 -1 (-775 1250)(-925 1250);
WIRE 16 -1 (-925 1300)(-925 1350);
WIRE 16 -1 (-775 1300)(-925 1300);
WIRE 16 -1 (-925 1350)(-925 1400);
WIRE 16 -1 (-775 1350)(-925 1350);
WIRE 16 -1 (-925 1400)(-925 1450);
WIRE 16 -1 (-775 1400)(-925 1400);
WIRE 16 -1 (-925 1450)(-925 1500);
WIRE 16 -1 (-775 1450)(-925 1450);
WIRE 16 -1 (-925 1500)(-925 1550);
WIRE 16 -1 (-775 1500)(-925 1500);
WIRE 16 -1 (-925 1550)(-925 1600);
WIRE 16 -1 (-775 1550)(-925 1550);
WIRE 16 -1 (-925 1600)(-925 1650);
WIRE 16 -1 (-775 1600)(-925 1600);
WIRE 16 -1 (-925 1650)(-925 1700);
WIRE 16 -1 (-775 1650)(-925 1650);
WIRE 16 -1 (-925 1700)(-925 1750);
WIRE 16 -1 (-775 1700)(-925 1700);
WIRE 16 -1 (-925 1750)(-925 1800);
WIRE 16 -1 (-775 1750)(-925 1750);
WIRE 16 -1 (-925 1800)(-925 1850);
WIRE 16 -1 (-775 1800)(-925 1800);
WIRE 16 -1 (-925 1850)(-925 1900);
WIRE 16 -1 (-775 1850)(-925 1850);
WIRE 16 -1 (-925 1900)(-925 1950);
WIRE 16 -1 (-775 1900)(-925 1900);
WIRE 16 -1 (-925 1950)(-925 2000);
WIRE 16 -1 (-775 1950)(-925 1950);
WIRE 16 -1 (-925 2000)(-925 2050);
WIRE 16 -1 (-775 2000)(-925 2000);
WIRE 16 -1 (-925 2050)(-925 2100);
WIRE 16 -1 (-775 2050)(-925 2050);
WIRE 16 -1 (-925 2100)(-925 2150);
WIRE 16 -1 (-775 2100)(-925 2100);
WIRE 16 -1 (-925 2150)(-925 2200);
WIRE 16 -1 (-775 2150)(-925 2150);
WIRE 16 -1 (-925 2200)(-925 2250);
WIRE 16 -1 (-775 2200)(-925 2200);
WIRE 16 -1 (-925 2250)(-925 2300);
WIRE 16 -1 (-775 2250)(-925 2250);
WIRE 16 -1 (-925 2300)(-925 2350);
WIRE 16 -1 (-775 2300)(-925 2300);
WIRE 16 -1 (-925 2350)(-925 2400);
WIRE 16 -1 (-775 2350)(-925 2350);
WIRE 16 -1 (-925 2400)(-925 2450);
WIRE 16 -1 (-775 2400)(-925 2400);
WIRE 16 -1 (-925 2450)(-925 2500);
WIRE 16 -1 (-775 2450)(-925 2450);
WIRE 16 -1 (-925 2500)(-925 2550);
WIRE 16 -1 (-775 2500)(-925 2500);
WIRE 16 -1 (-925 2550)(-925 2600);
WIRE 16 -1 (-775 2550)(-925 2550);
WIRE 16 -1 (-925 2600)(-925 2650);
WIRE 16 -1 (-775 2600)(-925 2600);
WIRE 16 -1 (-925 2650)(-925 2700);
WIRE 16 -1 (-775 2650)(-925 2650);
WIRE 16 -1 (-925 2700)(-925 2750);
WIRE 16 -1 (-775 2700)(-925 2700);
WIRE 16 -1 (-925 2750)(-925 2800);
WIRE 16 -1 (-775 2750)(-925 2750);
WIRE 16 -1 (-925 2800)(-925 2850);
WIRE 16 -1 (-775 2800)(-925 2800);
WIRE 16 -1 (-925 2850)(-925 2900);
WIRE 16 -1 (-775 2850)(-925 2850);
WIRE 16 -1 (-925 2900)(-925 2950);
WIRE 16 -1 (-775 2900)(-925 2900);
WIRE 16 -1 (-925 2950)(-925 3000);
WIRE 16 -1 (-775 2950)(-925 2950);
WIRE 16 -1 (-925 3000)(-925 3050);
WIRE 16 -1 (-775 3000)(-925 3000);
WIRE 16 -1 (-925 3050)(-925 3100);
WIRE 16 -1 (-775 3050)(-925 3050);
WIRE 16 -1 (-925 3100)(-925 3150);
WIRE 16 -1 (-775 3100)(-925 3100);
WIRE 16 -1 (-925 3150)(-925 3200);
WIRE 16 -1 (-775 3150)(-925 3150);
WIRE 16 -1 (-925 3200)(-925 3250);
WIRE 16 -1 (-775 3200)(-925 3200);
WIRE 16 -1 (-925 3250)(-925 3300);
WIRE 16 -1 (-775 3250)(-925 3250);
WIRE 16 -1 (-925 3300)(-925 3350);
WIRE 16 -1 (-775 3300)(-925 3300);
WIRE 16 -1 (-925 3350)(-925 3400);
WIRE 16 -1 (-775 3350)(-925 3350);
WIRE 16 -1 (-925 3400)(-925 3450);
WIRE 16 -1 (-775 3400)(-925 3400);
WIRE 16 -1 (-925 3450)(-925 3500);
WIRE 16 -1 (-775 3450)(-925 3450);
WIRE 16 -1 (-925 3500)(-925 3550);
WIRE 16 -1 (-775 3500)(-925 3500);
WIRE 16 -1 (-925 3550)(-925 3600);
WIRE 16 -1 (-775 3550)(-925 3550);
WIRE 16 -1 (-925 3600)(-925 3650);
WIRE 16 -1 (-775 3600)(-925 3600);
WIRE 16 -1 (-925 3650)(-925 3700);
WIRE 16 -1 (-775 3650)(-925 3650);
WIRE 16 -1 (-925 3700)(-925 3750);
WIRE 16 -1 (-775 3700)(-925 3700);
WIRE 16 -1 (-925 3750)(-925 3800);
WIRE 16 -1 (-775 3750)(-925 3750);
WIRE 16 -1 (-925 3800)(-925 3850);
WIRE 16 -1 (-775 3800)(-925 3800);
WIRE 16 -1 (-925 3850)(-925 3900);
WIRE 16 -1 (-775 3850)(-925 3850);
WIRE 16 -1 (-925 3900)(-925 3950);
WIRE 16 -1 (-775 3900)(-925 3900);
WIRE 16 -1 (-925 3950)(-925 4000);
WIRE 16 -1 (-775 3950)(-925 3950);
WIRE 16 -1 (-925 4000)(-925 4050);
WIRE 16 -1 (-775 4000)(-925 4000);
WIRE 16 -1 (-925 4050)(-925 4100);
WIRE 16 -1 (-775 4050)(-925 4050);
WIRE 16 -1 (-925 4100)(-925 4150);
WIRE 16 -1 (-775 4100)(-925 4100);
WIRE 16 -1 (-925 4150)(-925 4200);
WIRE 16 -1 (-775 4150)(-925 4150);
WIRE 16 -1 (-925 4200)(-925 4250);
WIRE 16 -1 (-775 4200)(-925 4200);
WIRE 16 -1 (-925 4250)(-925 4300);
WIRE 16 -1 (-775 4250)(-925 4250);
WIRE 16 -1 (-925 4300)(-925 4350);
WIRE 16 -1 (-775 4300)(-925 4300);
WIRE 16 -1 (-925 4350)(-925 4400);
WIRE 16 -1 (-775 4350)(-925 4350);
WIRE 16 -1 (-925 4400)(-925 4450);
WIRE 16 -1 (-775 4400)(-925 4400);
WIRE 16 -1 (-925 4450)(-925 4500);
WIRE 16 -1 (-775 4450)(-925 4450);
WIRE 16 -1 (-925 4500)(-925 4550);
WIRE 16 -1 (-775 4500)(-925 4500);
WIRE 16 -1 (-925 4550)(-925 4600);
WIRE 16 -1 (-775 4550)(-925 4550);
WIRE 16 -1 (-925 4650)(-925 4600);
WIRE 16 -1 (-775 4600)(-925 4600);
WIRE 16 -1 (-775 4650)(-925 4650);
WIRE 16 -1 (600 1700)(600 2000);
WIRE 16 -1 (600 2000)(600 2050);
WIRE 16 -1 (425 2000)(600 2000);
WIRE 16 -1 (600 2050)(600 2100);
WIRE 16 -1 (425 2050)(600 2050);
WIRE 16 -1 (600 2100)(600 2150);
WIRE 16 -1 (425 2100)(600 2100);
WIRE 16 -1 (600 2150)(600 2200);
WIRE 16 -1 (425 2150)(600 2150);
WIRE 16 -1 (600 2200)(600 2250);
WIRE 16 -1 (425 2200)(600 2200);
WIRE 16 -1 (600 2250)(600 2300);
WIRE 16 -1 (425 2250)(600 2250);
WIRE 16 -1 (600 2300)(600 2350);
WIRE 16 -1 (425 2300)(600 2300);
WIRE 16 -1 (600 2350)(600 2400);
WIRE 16 -1 (425 2350)(600 2350);
WIRE 16 -1 (600 2400)(600 2450);
WIRE 16 -1 (425 2400)(600 2400);
WIRE 16 -1 (600 2450)(600 2500);
WIRE 16 -1 (425 2450)(600 2450);
WIRE 16 -1 (600 2500)(600 2550);
WIRE 16 -1 (425 2500)(600 2500);
WIRE 16 -1 (600 2550)(600 2600);
WIRE 16 -1 (425 2550)(600 2550);
WIRE 16 -1 (600 2600)(600 2650);
WIRE 16 -1 (425 2600)(600 2600);
WIRE 16 -1 (600 2650)(600 2700);
WIRE 16 -1 (425 2650)(600 2650);
WIRE 16 -1 (600 2700)(600 2750);
WIRE 16 -1 (425 2700)(600 2700);
WIRE 16 -1 (600 2750)(600 2800);
WIRE 16 -1 (425 2750)(600 2750);
WIRE 16 -1 (600 2800)(600 2850);
WIRE 16 -1 (425 2800)(600 2800);
WIRE 16 -1 (600 2850)(600 2900);
WIRE 16 -1 (425 2850)(600 2850);
WIRE 16 -1 (600 2900)(600 2950);
WIRE 16 -1 (425 2900)(600 2900);
WIRE 16 -1 (600 2950)(600 3000);
WIRE 16 -1 (425 2950)(600 2950);
WIRE 16 -1 (600 3000)(600 3050);
WIRE 16 -1 (425 3000)(600 3000);
WIRE 16 -1 (600 3050)(600 3100);
WIRE 16 -1 (425 3050)(600 3050);
WIRE 16 -1 (600 3100)(600 3150);
WIRE 16 -1 (425 3100)(600 3100);
WIRE 16 -1 (600 3150)(600 3200);
WIRE 16 -1 (425 3150)(600 3150);
WIRE 16 -1 (600 3200)(600 3250);
WIRE 16 -1 (425 3200)(600 3200);
WIRE 16 -1 (600 3250)(600 3300);
WIRE 16 -1 (425 3250)(600 3250);
WIRE 16 -1 (600 3300)(600 3350);
WIRE 16 -1 (425 3300)(600 3300);
WIRE 16 -1 (600 3350)(600 3400);
WIRE 16 -1 (425 3350)(600 3350);
WIRE 16 -1 (600 3400)(600 3450);
WIRE 16 -1 (425 3400)(600 3400);
WIRE 16 -1 (600 3450)(600 3500);
WIRE 16 -1 (425 3450)(600 3450);
WIRE 16 -1 (600 3500)(600 3550);
WIRE 16 -1 (425 3500)(600 3500);
WIRE 16 -1 (600 3550)(600 3600);
WIRE 16 -1 (425 3550)(600 3550);
WIRE 16 -1 (600 3600)(600 3650);
WIRE 16 -1 (425 3600)(600 3600);
WIRE 16 -1 (600 3650)(600 3700);
WIRE 16 -1 (425 3650)(600 3650);
WIRE 16 -1 (600 3700)(600 3750);
WIRE 16 -1 (425 3700)(600 3700);
WIRE 16 -1 (600 3750)(600 3800);
WIRE 16 -1 (425 3750)(600 3750);
WIRE 16 -1 (600 3800)(600 3850);
WIRE 16 -1 (425 3800)(600 3800);
WIRE 16 -1 (600 3850)(600 3900);
WIRE 16 -1 (425 3850)(600 3850);
WIRE 16 -1 (600 3900)(600 3950);
WIRE 16 -1 (425 3900)(600 3900);
WIRE 16 -1 (600 3950)(600 4000);
WIRE 16 -1 (425 3950)(600 3950);
WIRE 16 -1 (600 4000)(600 4050);
WIRE 16 -1 (425 4000)(600 4000);
WIRE 16 -1 (600 4050)(600 4100);
WIRE 16 -1 (425 4050)(600 4050);
WIRE 16 -1 (600 4100)(600 4150);
WIRE 16 -1 (425 4100)(600 4100);
WIRE 16 -1 (600 4150)(600 4200);
WIRE 16 -1 (425 4150)(600 4150);
WIRE 16 -1 (600 4200)(600 4250);
WIRE 16 -1 (425 4200)(600 4200);
WIRE 16 -1 (600 4250)(600 4300);
WIRE 16 -1 (425 4250)(600 4250);
WIRE 16 -1 (600 4300)(600 4350);
WIRE 16 -1 (425 4300)(600 4300);
WIRE 16 -1 (600 4350)(600 4400);
WIRE 16 -1 (425 4350)(600 4350);
WIRE 16 -1 (600 4400)(600 4450);
WIRE 16 -1 (425 4400)(600 4400);
WIRE 16 -1 (600 4450)(600 4500);
WIRE 16 -1 (425 4450)(600 4450);
WIRE 16 -1 (600 4500)(600 4550);
WIRE 16 -1 (425 4500)(600 4500);
WIRE 16 -1 (600 4550)(600 4600);
WIRE 16 -1 (425 4550)(600 4550);
WIRE 16 -1 (600 4650)(600 4600);
WIRE 16 -1 (425 4600)(600 4600);
WIRE 16 -1 (425 4650)(600 4650);
DOT 1 (-2625 3800);
DOT 1 (-6025 4350);
DOT 1 (-2800 2850);
DOT 1 (-4475 1050);
DOT 1 (-4475 4550);
DOT 1 (-6025 4550);
DOT 1 (-6025 4600);
DOT 1 (-4475 4600);
DOT 1 (-1075 1150);
DOT 1 (-1075 1200);
DOT 1 (-2625 750);
DOT 1 (-4350 1550);
DOT 1 (-4350 1500);
DOT 1 (-4350 1450);
DOT 1 (-6025 1250);
DOT 1 (-4350 1600);
DOT 1 (-4350 1650);
DOT 1 (-4475 1800);
DOT 1 (-4475 1850);
DOT 1 (-2625 4550);
DOT 1 (-2625 4450);
DOT 1 (-2625 4400);
DOT 1 (-2625 4350);
DOT 1 (-2625 4300);
DOT 1 (-2625 4250);
DOT 1 (-2625 4150);
DOT 1 (-2625 4200);
DOT 1 (-2625 4100);
DOT 1 (-2625 4050);
DOT 1 (-2625 4000);
DOT 1 (-2625 3900);
DOT 1 (-2625 3950);
DOT 1 (-2625 3850);
DOT 1 (-2625 3750);
DOT 1 (-2625 3650);
DOT 1 (-2625 3700);
DOT 1 (-2625 3600);
DOT 1 (-2625 3550);
DOT 1 (-2625 3500);
DOT 1 (-2625 3400);
DOT 1 (-2625 3450);
DOT 1 (-2625 3350);
DOT 1 (-2625 3300);
DOT 1 (-2625 3250);
DOT 1 (-2625 3200);
DOT 1 (-2625 3150);
DOT 1 (-2625 3100);
DOT 1 (-2625 3050);
DOT 1 (-2625 3000);
DOT 1 (-2625 2950);
DOT 1 (-2625 2900);
DOT 1 (-2625 2850);
DOT 1 (-2625 2750);
DOT 1 (-2625 2800);
DOT 1 (-2625 2700);
DOT 1 (-2625 2650);
DOT 1 (-2625 2600);
DOT 1 (-2625 2550);
DOT 1 (-2625 2500);
DOT 1 (-2625 2450);
DOT 1 (-2625 2400);
DOT 1 (-2625 2350);
DOT 1 (-2625 2250);
DOT 1 (-2625 2300);
DOT 1 (-2625 2200);
DOT 1 (-2625 2150);
DOT 1 (-2625 2100);
DOT 1 (-2625 2050);
DOT 1 (-2625 2000);
DOT 1 (-2625 1950);
DOT 1 (-2625 1850);
DOT 1 (-2625 1900);
DOT 1 (-2625 1800);
DOT 1 (-2625 1750);
DOT 1 (-2625 1600);
DOT 1 (-2625 1650);
DOT 1 (-2625 1550);
DOT 1 (-2625 1500);
DOT 1 (-2625 1450);
DOT 1 (-2625 1350);
DOT 1 (-2625 1400);
DOT 1 (-2625 1300);
DOT 1 (-2625 1250);
DOT 1 (-2625 1200);
DOT 1 (-2625 1150);
DOT 1 (-2625 1100);
DOT 1 (-2625 1050);
DOT 1 (-2625 1000);
DOT 1 (-2625 950);
DOT 1 (-2625 900);
DOT 1 (-2625 850);
DOT 1 (-2625 800);
DOT 1 (-2625 700);
DOT 1 (-2625 650);
DOT 1 (-4350 4600);
DOT 1 (-4350 4550);
DOT 1 (-4350 4500);
DOT 1 (-4350 4450);
DOT 1 (-4350 4400);
DOT 1 (-4350 4350);
DOT 1 (-4350 4300);
DOT 1 (-4350 4200);
DOT 1 (-4350 4250);
DOT 1 (-4350 4150);
DOT 1 (-4350 4100);
DOT 1 (-4350 4050);
DOT 1 (-4350 3950);
DOT 1 (-4350 4000);
DOT 1 (-4350 3900);
DOT 1 (-4350 3850);
DOT 1 (-4350 3800);
DOT 1 (-4350 3700);
DOT 1 (-4350 3650);
DOT 1 (-4350 3600);
DOT 1 (-4350 3550);
DOT 1 (-4350 3450);
DOT 1 (-4350 3500);
DOT 1 (-4350 3400);
DOT 1 (-4350 3350);
DOT 1 (-4350 3300);
DOT 1 (-4350 3250);
DOT 1 (-4350 3200);
DOT 1 (-4350 3150);
DOT 1 (-4350 3100);
DOT 1 (-4350 3050);
DOT 1 (-4350 2950);
DOT 1 (-4350 2900);
DOT 1 (-4350 2800);
DOT 1 (-4350 2850);
DOT 1 (-4350 2750);
DOT 1 (-4350 2700);
DOT 1 (-4350 2650);
DOT 1 (-4350 2600);
DOT 1 (-4350 2550);
DOT 1 (-4350 2500);
DOT 1 (-4350 2450);
DOT 1 (-4350 2400);
DOT 1 (-4350 2300);
DOT 1 (-4350 2350);
DOT 1 (-4350 2250);
DOT 1 (-4350 2200);
DOT 1 (-4350 2150);
DOT 1 (-4350 2100);
DOT 1 (-4350 2050);
DOT 1 (-4350 2000);
DOT 1 (-4350 1900);
DOT 1 (-4350 1950);
DOT 1 (-4350 1800);
DOT 1 (-4350 1750);
DOT 1 (-4350 1700);
DOT 1 (-4350 1400);
DOT 1 (-4350 1350);
DOT 1 (-4350 1300);
DOT 1 (-4350 1250);
DOT 1 (-4350 1200);
DOT 1 (-4350 1150);
DOT 1 (-4350 1100);
DOT 1 (-4350 1050);
DOT 1 (-4350 1000);
DOT 1 (-4350 950);
DOT 1 (-4350 900);
DOT 1 (-4350 850);
DOT 1 (-4350 750);
DOT 1 (-4350 800);
DOT 1 (-4350 700);
DOT 1 (-6025 4500);
DOT 1 (-6025 4450);
DOT 1 (-6025 4400);
DOT 1 (-6025 4300);
DOT 1 (-6025 4250);
DOT 1 (-6025 4200);
DOT 1 (-6025 4100);
DOT 1 (-6025 4150);
DOT 1 (-6025 4050);
DOT 1 (-6025 4000);
DOT 1 (-6025 3950);
DOT 1 (-6025 3850);
DOT 1 (-6025 3900);
DOT 1 (-6025 3800);
DOT 1 (-6025 3750);
DOT 1 (-6025 3700);
DOT 1 (-6025 3600);
DOT 1 (-6025 3650);
DOT 1 (-6025 3550);
DOT 1 (-6025 3500);
DOT 1 (-6025 3450);
DOT 1 (-6025 3350);
DOT 1 (-6025 3400);
DOT 1 (-6025 3300);
DOT 1 (-6025 3250);
DOT 1 (-6025 3200);
DOT 1 (-6025 3150);
DOT 1 (-6025 3100);
DOT 1 (-6025 3050);
DOT 1 (-6025 3000);
DOT 1 (-6025 2950);
DOT 1 (-6025 2900);
DOT 1 (-6025 2850);
DOT 1 (-6025 2800);
DOT 1 (-6025 2700);
DOT 1 (-6025 2750);
DOT 1 (-6025 2650);
DOT 1 (-6025 2600);
DOT 1 (-6025 2550);
DOT 1 (-6025 2500);
DOT 1 (-6025 2450);
DOT 1 (-6025 2400);
DOT 1 (-6025 2350);
DOT 1 (-6025 2300);
DOT 1 (-6025 2200);
DOT 1 (-6025 2250);
DOT 1 (-6025 2150);
DOT 1 (-6025 2100);
DOT 1 (-6025 2050);
DOT 1 (-6025 2000);
DOT 1 (-6025 1950);
DOT 1 (-6025 1900);
DOT 1 (-6025 1800);
DOT 1 (-6025 1850);
DOT 1 (-6025 1750);
DOT 1 (-6025 1700);
DOT 1 (-6025 1650);
DOT 1 (-6025 1550);
DOT 1 (-6025 1600);
DOT 1 (-6025 1500);
DOT 1 (-6025 1450);
DOT 1 (-6025 1400);
DOT 1 (-6025 1300);
DOT 1 (-6025 1350);
DOT 1 (-6025 1200);
DOT 1 (-6025 1150);
DOT 1 (-6025 1100);
DOT 1 (-6025 1050);
DOT 1 (-6025 1000);
DOT 1 (-6025 950);
DOT 1 (-6025 900);
DOT 1 (-6025 850);
DOT 1 (-6025 800);
DOT 1 (-6025 750);
DOT 1 (-6025 700);
DOT 1 (-1075 3250);
DOT 1 (-1075 3150);
DOT 1 (-1075 3200);
DOT 1 (-1075 3100);
DOT 1 (-1075 3000);
DOT 1 (-1075 3050);
DOT 1 (-1075 2900);
DOT 1 (-1075 2950);
DOT 1 (-1075 2850);
DOT 1 (-1075 2800);
DOT 1 (-1075 2750);
DOT 1 (-1075 2650);
DOT 1 (-1075 2700);
DOT 1 (-1075 2550);
DOT 1 (-1075 2500);
DOT 1 (-1075 2350);
DOT 1 (-1075 2400);
DOT 1 (-1075 2450);
DOT 1 (-1075 2300);
DOT 1 (-1075 2250);
DOT 1 (-1075 2100);
DOT 1 (-1075 2150);
DOT 1 (-1075 2200);
DOT 1 (-1075 2000);
DOT 1 (-1075 2050);
DOT 1 (-1075 1950);
DOT 1 (-1075 1850);
DOT 1 (-1075 1900);
DOT 1 (-1075 1750);
DOT 1 (-1075 1800);
DOT 1 (-1075 1700);
DOT 1 (-1075 1600);
DOT 1 (-1075 1650);
DOT 1 (-1075 1450);
DOT 1 (-1075 1550);
DOT 1 (-1075 1500);
DOT 1 (-1075 1400);
DOT 1 (-1075 1350);
DOT 1 (-1075 1300);
DOT 1 (-1075 1250);
DOT 1 (-1075 1100);
DOT 1 (-1075 1050);
DOT 1 (-1075 950);
DOT 1 (-1075 1000);
DOT 1 (-1075 850);
DOT 1 (-1075 900);
DOT 1 (-1075 800);
DOT 1 (-1075 750);
DOT 1 (-1075 700);
DOT 1 (-1075 650);
DOT 1 (-2800 4600);
DOT 1 (-2800 4450);
DOT 1 (-2800 4550);
DOT 1 (-2800 4500);
DOT 1 (-2800 4350);
DOT 1 (-2800 4400);
DOT 1 (-2800 4300);
DOT 1 (-2800 4200);
DOT 1 (-2800 4250);
DOT 1 (-2800 4100);
DOT 1 (-2800 4150);
DOT 1 (-2800 4050);
DOT 1 (-2800 3950);
DOT 1 (-2800 4000);
DOT 1 (-2800 3850);
DOT 1 (-2800 3900);
DOT 1 (-2800 3700);
DOT 1 (-2800 3750);
DOT 1 (-2800 3650);
DOT 1 (-2800 3450);
DOT 1 (-2800 3500);
DOT 1 (-2800 3300);
DOT 1 (-2800 3400);
DOT 1 (-2800 3350);
DOT 1 (-2800 3200);
DOT 1 (-2800 3250);
DOT 1 (-2800 3150);
DOT 1 (-2800 3050);
DOT 1 (-2800 3100);
DOT 1 (-2800 2950);
DOT 1 (-2800 3000);
DOT 1 (-2800 2900);
DOT 1 (-2800 2800);
DOT 1 (-2800 2650);
DOT 1 (-2800 2700);
DOT 1 (-2800 2750);
DOT 1 (-2800 2600);
DOT 1 (-2800 2550);
DOT 1 (-2800 2400);
DOT 1 (-2800 2450);
DOT 1 (-2800 2500);
DOT 1 (-2800 2350);
DOT 1 (-2800 2300);
DOT 1 (-2800 2150);
DOT 1 (-2800 2200);
DOT 1 (-2800 2250);
DOT 1 (-2800 2050);
DOT 1 (-2800 2100);
DOT 1 (-2800 2000);
DOT 1 (-2800 1900);
DOT 1 (-2800 1800);
DOT 1 (-2800 1850);
DOT 1 (-2800 1750);
DOT 1 (-2800 1650);
DOT 1 (-2800 1700);
DOT 1 (-2800 1500);
DOT 1 (-2800 1450);
DOT 1 (-2800 1400);
DOT 1 (-2800 1250);
DOT 1 (-2800 1350);
DOT 1 (-2800 1300);
DOT 1 (-2800 1150);
DOT 1 (-2800 1200);
DOT 1 (-2800 1100);
DOT 1 (-2800 1000);
DOT 1 (-2800 1050);
DOT 1 (-2800 900);
DOT 1 (-2800 950);
DOT 1 (-2800 850);
DOT 1 (-2800 800);
DOT 1 (-2800 750);
DOT 1 (-2800 700);
DOT 1 (-4475 4500);
DOT 1 (-4475 4350);
DOT 1 (-4475 4450);
DOT 1 (-4475 4400);
DOT 1 (-4475 4250);
DOT 1 (-4475 4300);
DOT 1 (-4475 4200);
DOT 1 (-4475 4100);
DOT 1 (-4475 4150);
DOT 1 (-4475 4000);
DOT 1 (-4475 4050);
DOT 1 (-4475 3950);
DOT 1 (-4475 3850);
DOT 1 (-4475 3900);
DOT 1 (-4475 3750);
DOT 1 (-4475 3800);
DOT 1 (-4475 3700);
DOT 1 (-4475 3600);
DOT 1 (-4475 3650);
DOT 1 (-4475 3450);
DOT 1 (-4475 3550);
DOT 1 (-4475 3500);
DOT 1 (-4475 3350);
DOT 1 (-4475 3200);
DOT 1 (-4475 3300);
DOT 1 (-4475 3250);
DOT 1 (-4475 3100);
DOT 1 (-4475 3150);
DOT 1 (-4475 3050);
DOT 1 (-4475 2950);
DOT 1 (-4475 3000);
DOT 1 (-4475 2850);
DOT 1 (-4475 2900);
DOT 1 (-4475 2800);
DOT 1 (-4475 2750);
DOT 1 (-4475 2700);
DOT 1 (-4475 2550);
DOT 1 (-4475 2600);
DOT 1 (-4475 2650);
DOT 1 (-4475 2500);
DOT 1 (-4475 2450);
DOT 1 (-4475 2300);
DOT 1 (-4475 2350);
DOT 1 (-4475 2400);
DOT 1 (-4475 2250);
DOT 1 (-4475 2200);
DOT 1 (-4475 2050);
DOT 1 (-4475 2100);
DOT 1 (-4475 2150);
DOT 1 (-4475 1950);
DOT 1 (-4475 2000);
DOT 1 (-4475 1900);
DOT 1 (-4475 1700);
DOT 1 (-4475 1750);
DOT 1 (-4475 1550);
DOT 1 (-4475 1600);
DOT 1 (-4475 1400);
DOT 1 (-4475 1500);
DOT 1 (-4475 1450);
DOT 1 (-4475 1350);
DOT 1 (-4475 1300);
DOT 1 (-4475 1150);
DOT 1 (-4475 1250);
DOT 1 (-4475 1200);
DOT 1 (-4475 1100);
DOT 1 (-4475 1000);
DOT 1 (-4475 900);
DOT 1 (-4475 950);
DOT 1 (-4475 800);
DOT 1 (-4475 850);
DOT 1 (-4475 750);
DOT 1 (-4475 700);
DOT 1 (-1075 3300);
DOT 1 (-1075 3450);
DOT 1 (-1075 3400);
DOT 1 (-1075 3550);
DOT 1 (-1075 3500);
DOT 1 (-1075 3600);
DOT 1 (-1075 3700);
DOT 1 (-1075 3650);
DOT 1 (-1075 3750);
DOT 1 (-1075 3800);
DOT 1 (-1075 3850);
DOT 1 (-1075 3950);
DOT 1 (-1075 3900);
DOT 1 (-1075 4000);
DOT 1 (-1075 4050);
DOT 1 (-1075 4100);
DOT 1 (-1075 4150);
DOT 1 (-1075 4300);
DOT 1 (-1075 4350);
DOT 1 (-1075 4250);
DOT 1 (-1075 4400);
DOT 1 (-1075 4450);
DOT 1 (-1075 4550);
DOT 1 (-1075 4500);
DOT 1 (-4475 1650);
DOT 1 (-2800 1550);
DOT 1 (-2800 1600);
DOT 1 (-2625 1700);
DOT 1 (-2800 3550);
DOT 1 (-4350 3750);
DOT 1 (-2800 1950);
DOT 1 (-4350 3000);
DOT 1 (-4475 3400);
DOT 1 (-2625 4500);
DOT 1 (-2800 3600);
DOT 1 (-925 4600);
DOT 1 (600 4600);
DOT 1 (-925 4550);
DOT 1 (600 4550);
DOT 1 (-925 4500);
DOT 1 (600 4500);
DOT 1 (-925 4450);
DOT 1 (600 4450);
DOT 1 (-925 4400);
DOT 1 (600 4400);
DOT 1 (-925 4350);
DOT 1 (600 4350);
DOT 1 (-925 4300);
DOT 1 (600 4300);
DOT 1 (-925 4250);
DOT 1 (600 4250);
DOT 1 (-925 4200);
DOT 1 (-925 4150);
DOT 1 (600 4150);
DOT 1 (-925 4100);
DOT 1 (600 4100);
DOT 1 (600 4050);
DOT 1 (-925 4000);
DOT 1 (600 4000);
DOT 1 (-925 3950);
DOT 1 (600 3950);
DOT 1 (-925 3900);
DOT 1 (600 3900);
DOT 1 (-925 3850);
DOT 1 (600 3850);
DOT 1 (-925 3800);
DOT 1 (600 3800);
DOT 1 (-925 3750);
DOT 1 (600 3750);
DOT 1 (-925 3700);
DOT 1 (600 3700);
DOT 1 (-925 3650);
DOT 1 (600 3650);
DOT 1 (-925 3600);
DOT 1 (600 3600);
DOT 1 (-925 3550);
DOT 1 (600 3550);
DOT 1 (-925 3500);
DOT 1 (600 3500);
DOT 1 (-925 3450);
DOT 1 (600 3450);
DOT 1 (-925 3400);
DOT 1 (600 3400);
DOT 1 (-925 3350);
DOT 1 (600 3350);
DOT 1 (-925 3300);
DOT 1 (600 3300);
DOT 1 (-925 3250);
DOT 1 (600 3250);
DOT 1 (-925 3200);
DOT 1 (600 3200);
DOT 1 (-925 3150);
DOT 1 (600 3150);
DOT 1 (-925 3100);
DOT 1 (600 3100);
DOT 1 (-925 3050);
DOT 1 (600 3050);
DOT 1 (-925 3000);
DOT 1 (600 3000);
DOT 1 (-925 2950);
DOT 1 (600 2950);
DOT 1 (-925 2900);
DOT 1 (600 2900);
DOT 1 (-925 2850);
DOT 1 (600 2850);
DOT 1 (-925 2800);
DOT 1 (600 2800);
DOT 1 (-925 2750);
DOT 1 (600 2750);
DOT 1 (-925 2700);
DOT 1 (600 2700);
DOT 1 (-925 2650);
DOT 1 (600 2650);
DOT 1 (-925 2600);
DOT 1 (600 2600);
DOT 1 (-925 2550);
DOT 1 (600 2550);
DOT 1 (-925 2500);
DOT 1 (600 2500);
DOT 1 (600 2450);
DOT 1 (-925 2400);
DOT 1 (600 2400);
DOT 1 (-925 2350);
DOT 1 (600 2350);
DOT 1 (-925 2300);
DOT 1 (600 2300);
DOT 1 (-925 2250);
DOT 1 (-925 2200);
DOT 1 (600 2200);
DOT 1 (-925 2150);
DOT 1 (600 2150);
DOT 1 (-925 2100);
DOT 1 (600 2100);
DOT 1 (-925 2050);
DOT 1 (600 2050);
DOT 1 (-925 2000);
DOT 1 (-925 1950);
DOT 1 (-925 1900);
DOT 1 (-925 1850);
DOT 1 (-925 1800);
DOT 1 (-925 1750);
DOT 1 (-925 1700);
DOT 1 (-925 1650);
DOT 1 (-925 1600);
DOT 1 (-925 1550);
DOT 1 (-925 1500);
DOT 1 (-925 1450);
DOT 1 (-925 1400);
DOT 1 (-925 1350);
DOT 1 (-925 1300);
DOT 1 (-925 1250);
DOT 1 (-925 1200);
DOT 1 (-925 1150);
DOT 1 (-925 1100);
DOT 1 (-925 1050);
DOT 1 (-925 1000);
DOT 1 (-925 950);
DOT 1 (-925 900);
DOT 1 (-925 850);
DOT 1 (-925 800);
DOT 1 (-925 750);
DOT 1 (-925 700);
DOT 1 (-1075 2600);
DOT 1 (-925 2450);
DOT 1 (600 4200);
DOT 1 (-1075 3350);
DOT 1 (600 2000);
DOT 1 (-2800 3800);
DOT 1 (-1075 4200);
DOT 1 (-925 4050);
DOT 1 (600 2250);
DOT 1 (-4350 1850);
FORCENOTE
SKYLAKE - SKT0 - 21 OF 21
(-125 225) 0;
DISPLAY LEFT (-125 225);
DISPLAY 1.021277 (-125 225);
PAINT RED (-125 225);
FORCENOTE
ROOM=CPU0
(-6375 400) 0;
DISPLAY LEFT (-6375 400);
DISPLAY 1.723404 (-6375 400);
PAINT PURPLE (-6375 400);
FORCENOTE
BOM_COST=PROC_SOCKET
(-6375 275) 0;
DISPLAY LEFT (-6375 275);
DISPLAY 1.723404 (-6375 275);
PAINT PURPLE (-6375 275);
QUIT
